FILE_TYPE = MACRO_DRAWING;
SET COLOR_WIRE YELLOW;
SET COLOR_PROP MONO;
SET COLOR_DOT WHITE;
SET COLOR_ARC YELLOW;
SET COLOR_BODY GREEN;
SET COLOR_NOTE MONO;
SET PROP_DISPLAY VALUE;
SET PAGE_NUMBER P117;
FORCEADD TAP..6
(-5500 2400);
FORCEPROP 3 LASTPIN (-5450 2400) SIG_NAME P3E_CPU0_PE1_PCH_C_TXN<12>
J 0
(-5440 2410);
DISPLAY 0.659574 (-5440 2410);
PAINT MONO (-5440 2410);
DISPLAY INVISIBLE (-5440 2410);
FORCEPROP 1 LASTPIN (-5450 2400) BN 12
J 0
(-5502 2408);
DISPLAY 0.617021 (-5502 2408);
PAINT GREEN (-5502 2408);
FORCEPROP 2 LAST CDS_LIB mstr_standard
J 0
(-5500 2400);
PAINT ORANGE (-5500 2400);
DISPLAY INVISIBLE (-5500 2400);
FORCEPROP 1 LAST BODY_TYPE PLUMBING
J 0
(-5500 2350);
DISPLAY 1.170213 (-5500 2350);
PAINT GREEN (-5500 2350);
DISPLAY INVISIBLE (-5500 2350);
FORCEPROP 1 LAST HDL_TAP TRUE
J 0
(-5175 2275);
DISPLAY 1.170213 (-5175 2275);
PAINT ORANGE (-5175 2275);
DISPLAY INVISIBLE (-5175 2275);
FORCEPROP 1 LAST PATH I101
J 0
(-5502 2400);
DISPLAY 0.872340 (-5502 2400);
PAINT GREEN (-5502 2400);
DISPLAY INVISIBLE (-5502 2400);
FORCEADD TAP..6
(-5500 2500);
FORCEPROP 3 LASTPIN (-5450 2500) SIG_NAME P3E_CPU0_PE1_PCH_C_TXN<13>
J 0
(-5440 2510);
DISPLAY 0.659574 (-5440 2510);
PAINT MONO (-5440 2510);
DISPLAY INVISIBLE (-5440 2510);
FORCEPROP 1 LASTPIN (-5450 2500) BN 13
J 0
(-5502 2508);
DISPLAY 0.617021 (-5502 2508);
PAINT GREEN (-5502 2508);
FORCEPROP 2 LAST CDS_LIB mstr_standard
J 0
(-5500 2500);
PAINT ORANGE (-5500 2500);
DISPLAY INVISIBLE (-5500 2500);
FORCEPROP 1 LAST BODY_TYPE PLUMBING
J 0
(-5500 2450);
DISPLAY 1.170213 (-5500 2450);
PAINT GREEN (-5500 2450);
DISPLAY INVISIBLE (-5500 2450);
FORCEPROP 1 LAST HDL_TAP TRUE
J 0
(-5175 2375);
DISPLAY 1.170213 (-5175 2375);
PAINT ORANGE (-5175 2375);
DISPLAY INVISIBLE (-5175 2375);
FORCEPROP 1 LAST PATH I102
J 0
(-5502 2500);
DISPLAY 0.872340 (-5502 2500);
PAINT GREEN (-5502 2500);
DISPLAY INVISIBLE (-5502 2500);
FORCEADD TAP..6
(-5500 2600);
FORCEPROP 3 LASTPIN (-5450 2600) SIG_NAME P3E_CPU0_PE1_PCH_C_TXN<14>
J 0
(-5440 2610);
DISPLAY 0.659574 (-5440 2610);
PAINT MONO (-5440 2610);
DISPLAY INVISIBLE (-5440 2610);
FORCEPROP 1 LASTPIN (-5450 2600) BN 14
J 0
(-5502 2608);
DISPLAY 0.617021 (-5502 2608);
PAINT GREEN (-5502 2608);
FORCEPROP 2 LAST CDS_LIB mstr_standard
J 0
(-5500 2600);
PAINT ORANGE (-5500 2600);
DISPLAY INVISIBLE (-5500 2600);
FORCEPROP 1 LAST BODY_TYPE PLUMBING
J 0
(-5500 2550);
DISPLAY 1.170213 (-5500 2550);
PAINT GREEN (-5500 2550);
DISPLAY INVISIBLE (-5500 2550);
FORCEPROP 1 LAST HDL_TAP TRUE
J 0
(-5175 2475);
DISPLAY 1.170213 (-5175 2475);
PAINT ORANGE (-5175 2475);
DISPLAY INVISIBLE (-5175 2475);
FORCEPROP 1 LAST PATH I103
J 0
(-5502 2600);
DISPLAY 0.872340 (-5502 2600);
PAINT GREEN (-5502 2600);
DISPLAY INVISIBLE (-5502 2600);
FORCEADD TAP..6
(-5500 2700);
FORCEPROP 3 LASTPIN (-5450 2700) SIG_NAME P3E_CPU0_PE1_PCH_C_TXN<15>
J 0
(-5440 2710);
DISPLAY 0.659574 (-5440 2710);
PAINT MONO (-5440 2710);
DISPLAY INVISIBLE (-5440 2710);
FORCEPROP 1 LASTPIN (-5450 2700) BN 15
J 0
(-5502 2708);
DISPLAY 0.617021 (-5502 2708);
PAINT GREEN (-5502 2708);
FORCEPROP 2 LAST CDS_LIB mstr_standard
J 0
(-5500 2700);
PAINT ORANGE (-5500 2700);
DISPLAY INVISIBLE (-5500 2700);
FORCEPROP 1 LAST BODY_TYPE PLUMBING
J 0
(-5500 2650);
DISPLAY 1.170213 (-5500 2650);
PAINT GREEN (-5500 2650);
DISPLAY INVISIBLE (-5500 2650);
FORCEPROP 1 LAST HDL_TAP TRUE
J 0
(-5175 2575);
DISPLAY 1.170213 (-5175 2575);
PAINT ORANGE (-5175 2575);
DISPLAY INVISIBLE (-5175 2575);
FORCEPROP 1 LAST PATH I104
J 0
(-5502 2700);
DISPLAY 0.872340 (-5502 2700);
PAINT GREEN (-5502 2700);
DISPLAY INVISIBLE (-5502 2700);
FORCEADD TAP..6
(-5625 1950);
FORCEPROP 3 LASTPIN (-5575 1950) SIG_NAME P3E_CPU0_PE1_PCH_C_TXP<8>
J 0
(-5565 1960);
DISPLAY 0.659574 (-5565 1960);
PAINT MONO (-5565 1960);
DISPLAY INVISIBLE (-5565 1960);
FORCEPROP 1 LASTPIN (-5575 1950) BN 8
J 0
(-5627 1958);
DISPLAY 0.617021 (-5627 1958);
PAINT GREEN (-5627 1958);
FORCEPROP 2 LAST CDS_LIB mstr_standard
J 0
(-5625 1950);
PAINT ORANGE (-5625 1950);
DISPLAY INVISIBLE (-5625 1950);
FORCEPROP 1 LAST BODY_TYPE PLUMBING
J 0
(-5625 1900);
DISPLAY 1.170213 (-5625 1900);
PAINT GREEN (-5625 1900);
DISPLAY INVISIBLE (-5625 1900);
FORCEPROP 1 LAST HDL_TAP TRUE
J 0
(-5300 1825);
DISPLAY 1.170213 (-5300 1825);
PAINT ORANGE (-5300 1825);
DISPLAY INVISIBLE (-5300 1825);
FORCEPROP 1 LAST PATH I105
J 0
(-5627 1950);
DISPLAY 0.872340 (-5627 1950);
PAINT GREEN (-5627 1950);
DISPLAY INVISIBLE (-5627 1950);
FORCEADD TAP..6
(-5625 2050);
FORCEPROP 3 LASTPIN (-5575 2050) SIG_NAME P3E_CPU0_PE1_PCH_C_TXP<9>
J 0
(-5565 2060);
DISPLAY 0.659574 (-5565 2060);
PAINT MONO (-5565 2060);
DISPLAY INVISIBLE (-5565 2060);
FORCEPROP 1 LASTPIN (-5575 2050) BN 9
J 0
(-5627 2058);
DISPLAY 0.617021 (-5627 2058);
PAINT GREEN (-5627 2058);
FORCEPROP 2 LAST CDS_LIB mstr_standard
J 0
(-5625 2050);
PAINT ORANGE (-5625 2050);
DISPLAY INVISIBLE (-5625 2050);
FORCEPROP 1 LAST BODY_TYPE PLUMBING
J 0
(-5625 2000);
DISPLAY 1.170213 (-5625 2000);
PAINT GREEN (-5625 2000);
DISPLAY INVISIBLE (-5625 2000);
FORCEPROP 1 LAST HDL_TAP TRUE
J 0
(-5300 1925);
DISPLAY 1.170213 (-5300 1925);
PAINT ORANGE (-5300 1925);
DISPLAY INVISIBLE (-5300 1925);
FORCEPROP 1 LAST PATH I106
J 0
(-5627 2050);
DISPLAY 0.872340 (-5627 2050);
PAINT GREEN (-5627 2050);
DISPLAY INVISIBLE (-5627 2050);
FORCEADD TAP..6
(-5625 2150);
FORCEPROP 3 LASTPIN (-5575 2150) SIG_NAME P3E_CPU0_PE1_PCH_C_TXP<10>
J 0
(-5565 2160);
DISPLAY 0.659574 (-5565 2160);
PAINT MONO (-5565 2160);
DISPLAY INVISIBLE (-5565 2160);
FORCEPROP 1 LASTPIN (-5575 2150) BN 10
J 0
(-5627 2158);
DISPLAY 0.617021 (-5627 2158);
PAINT GREEN (-5627 2158);
FORCEPROP 2 LAST CDS_LIB mstr_standard
J 0
(-5625 2150);
PAINT ORANGE (-5625 2150);
DISPLAY INVISIBLE (-5625 2150);
FORCEPROP 1 LAST BODY_TYPE PLUMBING
J 0
(-5625 2100);
DISPLAY 1.170213 (-5625 2100);
PAINT GREEN (-5625 2100);
DISPLAY INVISIBLE (-5625 2100);
FORCEPROP 1 LAST HDL_TAP TRUE
J 0
(-5300 2025);
DISPLAY 1.170213 (-5300 2025);
PAINT ORANGE (-5300 2025);
DISPLAY INVISIBLE (-5300 2025);
FORCEPROP 1 LAST PATH I107
J 0
(-5627 2150);
DISPLAY 0.872340 (-5627 2150);
PAINT GREEN (-5627 2150);
DISPLAY INVISIBLE (-5627 2150);
FORCEADD TAP..6
(-5625 2350);
FORCEPROP 3 LASTPIN (-5575 2350) SIG_NAME P3E_CPU0_PE1_PCH_C_TXP<12>
J 0
(-5565 2360);
DISPLAY 0.659574 (-5565 2360);
PAINT MONO (-5565 2360);
DISPLAY INVISIBLE (-5565 2360);
FORCEPROP 1 LASTPIN (-5575 2350) BN 12
J 0
(-5627 2358);
DISPLAY 0.617021 (-5627 2358);
PAINT GREEN (-5627 2358);
FORCEPROP 2 LAST CDS_LIB mstr_standard
J 0
(-5625 2350);
PAINT ORANGE (-5625 2350);
DISPLAY INVISIBLE (-5625 2350);
FORCEPROP 1 LAST BODY_TYPE PLUMBING
J 0
(-5625 2300);
DISPLAY 1.170213 (-5625 2300);
PAINT GREEN (-5625 2300);
DISPLAY INVISIBLE (-5625 2300);
FORCEPROP 1 LAST HDL_TAP TRUE
J 0
(-5300 2225);
DISPLAY 1.170213 (-5300 2225);
PAINT ORANGE (-5300 2225);
DISPLAY INVISIBLE (-5300 2225);
FORCEPROP 1 LAST PATH I109
J 0
(-5627 2350);
DISPLAY 0.872340 (-5627 2350);
PAINT GREEN (-5627 2350);
DISPLAY INVISIBLE (-5627 2350);
FORCEADD TAP..6
(-5625 2450);
FORCEPROP 3 LASTPIN (-5575 2450) SIG_NAME P3E_CPU0_PE1_PCH_C_TXP<13>
J 0
(-5565 2460);
DISPLAY 0.659574 (-5565 2460);
PAINT MONO (-5565 2460);
DISPLAY INVISIBLE (-5565 2460);
FORCEPROP 1 LASTPIN (-5575 2450) BN 13
J 0
(-5627 2458);
DISPLAY 0.617021 (-5627 2458);
PAINT GREEN (-5627 2458);
FORCEPROP 2 LAST CDS_LIB mstr_standard
J 0
(-5625 2450);
PAINT ORANGE (-5625 2450);
DISPLAY INVISIBLE (-5625 2450);
FORCEPROP 1 LAST BODY_TYPE PLUMBING
J 0
(-5625 2400);
DISPLAY 1.170213 (-5625 2400);
PAINT GREEN (-5625 2400);
DISPLAY INVISIBLE (-5625 2400);
FORCEPROP 1 LAST HDL_TAP TRUE
J 0
(-5300 2325);
DISPLAY 1.170213 (-5300 2325);
PAINT ORANGE (-5300 2325);
DISPLAY INVISIBLE (-5300 2325);
FORCEPROP 1 LAST PATH I110
J 0
(-5627 2450);
DISPLAY 0.872340 (-5627 2450);
PAINT GREEN (-5627 2450);
DISPLAY INVISIBLE (-5627 2450);
FORCEADD TAP..6
(-5625 2550);
FORCEPROP 3 LASTPIN (-5575 2550) SIG_NAME P3E_CPU0_PE1_PCH_C_TXP<14>
J 0
(-5565 2560);
DISPLAY 0.659574 (-5565 2560);
PAINT MONO (-5565 2560);
DISPLAY INVISIBLE (-5565 2560);
FORCEPROP 1 LASTPIN (-5575 2550) BN 14
J 0
(-5627 2558);
DISPLAY 0.617021 (-5627 2558);
PAINT GREEN (-5627 2558);
FORCEPROP 2 LAST CDS_LIB mstr_standard
J 0
(-5625 2550);
PAINT ORANGE (-5625 2550);
DISPLAY INVISIBLE (-5625 2550);
FORCEPROP 1 LAST BODY_TYPE PLUMBING
J 0
(-5625 2500);
DISPLAY 1.170213 (-5625 2500);
PAINT GREEN (-5625 2500);
DISPLAY INVISIBLE (-5625 2500);
FORCEPROP 1 LAST HDL_TAP TRUE
J 0
(-5300 2425);
DISPLAY 1.170213 (-5300 2425);
PAINT ORANGE (-5300 2425);
DISPLAY INVISIBLE (-5300 2425);
FORCEPROP 1 LAST PATH I111
J 0
(-5627 2550);
DISPLAY 0.872340 (-5627 2550);
PAINT GREEN (-5627 2550);
DISPLAY INVISIBLE (-5627 2550);
FORCEADD TAP..6
(-5625 2650);
FORCEPROP 3 LASTPIN (-5575 2650) SIG_NAME P3E_CPU0_PE1_PCH_C_TXP<15>
J 0
(-5565 2660);
DISPLAY 0.659574 (-5565 2660);
PAINT MONO (-5565 2660);
DISPLAY INVISIBLE (-5565 2660);
FORCEPROP 1 LASTPIN (-5575 2650) BN 15
J 0
(-5627 2658);
DISPLAY 0.617021 (-5627 2658);
PAINT GREEN (-5627 2658);
FORCEPROP 2 LAST CDS_LIB mstr_standard
J 0
(-5625 2650);
PAINT ORANGE (-5625 2650);
DISPLAY INVISIBLE (-5625 2650);
FORCEPROP 1 LAST BODY_TYPE PLUMBING
J 0
(-5625 2600);
DISPLAY 1.170213 (-5625 2600);
PAINT GREEN (-5625 2600);
DISPLAY INVISIBLE (-5625 2600);
FORCEPROP 1 LAST HDL_TAP TRUE
J 0
(-5300 2525);
DISPLAY 1.170213 (-5300 2525);
PAINT ORANGE (-5300 2525);
DISPLAY INVISIBLE (-5300 2525);
FORCEPROP 1 LAST PATH I112
J 0
(-5627 2650);
DISPLAY 0.872340 (-5627 2650);
PAINT GREEN (-5627 2650);
DISPLAY INVISIBLE (-5627 2650);
FORCEADD TAP..1
(-2600 1950);
FORCEPROP 3 LASTPIN (-2650 1950) SIG_NAME P3E_CPU0_PE1_PCH_R_RXN<8>
J 0
(-2640 1960);
DISPLAY 0.659574 (-2640 1960);
PAINT MONO (-2640 1960);
DISPLAY INVISIBLE (-2640 1960);
FORCEPROP 1 LASTPIN (-2650 1950) BN 8
J 0
(-2662 1958);
DISPLAY 0.617021 (-2662 1958);
PAINT GREEN (-2662 1958);
FORCEPROP 2 LAST CDS_LIB mstr_standard
J 0
(-2600 1950);
PAINT ORANGE (-2600 1950);
DISPLAY INVISIBLE (-2600 1950);
FORCEPROP 1 LAST BODY_TYPE PLUMBING
J 0
(-2600 2000);
DISPLAY 1.170213 (-2600 2000);
PAINT GREEN (-2600 2000);
DISPLAY INVISIBLE (-2600 2000);
FORCEPROP 1 LAST HDL_TAP TRUE
J 0
(-2275 1825);
DISPLAY 1.170213 (-2275 1825);
PAINT ORANGE (-2275 1825);
DISPLAY INVISIBLE (-2275 1825);
FORCEPROP 1 LAST PATH I113
J 0
(-2602 1950);
DISPLAY 0.872340 (-2602 1950);
PAINT GREEN (-2602 1950);
DISPLAY INVISIBLE (-2602 1950);
FORCEADD TAP..1
(-2600 2050);
FORCEPROP 3 LASTPIN (-2650 2050) SIG_NAME P3E_CPU0_PE1_PCH_R_RXN<9>
J 0
(-2640 2060);
DISPLAY 0.659574 (-2640 2060);
PAINT MONO (-2640 2060);
DISPLAY INVISIBLE (-2640 2060);
FORCEPROP 1 LASTPIN (-2650 2050) BN 9
J 0
(-2662 2058);
DISPLAY 0.617021 (-2662 2058);
PAINT GREEN (-2662 2058);
FORCEPROP 2 LAST CDS_LIB mstr_standard
J 0
(-2600 2050);
PAINT ORANGE (-2600 2050);
DISPLAY INVISIBLE (-2600 2050);
FORCEPROP 1 LAST BODY_TYPE PLUMBING
J 0
(-2600 2100);
DISPLAY 1.170213 (-2600 2100);
PAINT GREEN (-2600 2100);
DISPLAY INVISIBLE (-2600 2100);
FORCEPROP 1 LAST HDL_TAP TRUE
J 0
(-2275 1925);
DISPLAY 1.170213 (-2275 1925);
PAINT ORANGE (-2275 1925);
DISPLAY INVISIBLE (-2275 1925);
FORCEPROP 1 LAST PATH I114
J 0
(-2602 2050);
DISPLAY 0.872340 (-2602 2050);
PAINT GREEN (-2602 2050);
DISPLAY INVISIBLE (-2602 2050);
FORCEADD TAP..1
(-2600 2150);
FORCEPROP 3 LASTPIN (-2650 2150) SIG_NAME P3E_CPU0_PE1_PCH_R_RXN<10>
J 0
(-2640 2160);
DISPLAY 0.659574 (-2640 2160);
PAINT MONO (-2640 2160);
DISPLAY INVISIBLE (-2640 2160);
FORCEPROP 1 LASTPIN (-2650 2150) BN 10
J 0
(-2662 2158);
DISPLAY 0.617021 (-2662 2158);
PAINT GREEN (-2662 2158);
FORCEPROP 2 LAST CDS_LIB mstr_standard
J 0
(-2600 2150);
PAINT ORANGE (-2600 2150);
DISPLAY INVISIBLE (-2600 2150);
FORCEPROP 1 LAST BODY_TYPE PLUMBING
J 0
(-2600 2200);
DISPLAY 1.170213 (-2600 2200);
PAINT GREEN (-2600 2200);
DISPLAY INVISIBLE (-2600 2200);
FORCEPROP 1 LAST HDL_TAP TRUE
J 0
(-2275 2025);
DISPLAY 1.170213 (-2275 2025);
PAINT ORANGE (-2275 2025);
DISPLAY INVISIBLE (-2275 2025);
FORCEPROP 1 LAST PATH I115
J 0
(-2602 2150);
DISPLAY 0.872340 (-2602 2150);
PAINT GREEN (-2602 2150);
DISPLAY INVISIBLE (-2602 2150);
FORCEADD TAP..1
(-2600 2250);
FORCEPROP 3 LASTPIN (-2650 2250) SIG_NAME P3E_CPU0_PE1_PCH_R_RXN<11>
J 0
(-2640 2260);
DISPLAY 0.659574 (-2640 2260);
PAINT MONO (-2640 2260);
DISPLAY INVISIBLE (-2640 2260);
FORCEPROP 1 LASTPIN (-2650 2250) BN 11
J 0
(-2662 2258);
DISPLAY 0.617021 (-2662 2258);
PAINT GREEN (-2662 2258);
FORCEPROP 2 LAST CDS_LIB mstr_standard
J 0
(-2600 2250);
PAINT ORANGE (-2600 2250);
DISPLAY INVISIBLE (-2600 2250);
FORCEPROP 1 LAST BODY_TYPE PLUMBING
J 0
(-2600 2300);
DISPLAY 1.170213 (-2600 2300);
PAINT GREEN (-2600 2300);
DISPLAY INVISIBLE (-2600 2300);
FORCEPROP 1 LAST HDL_TAP TRUE
J 0
(-2275 2125);
DISPLAY 1.170213 (-2275 2125);
PAINT ORANGE (-2275 2125);
DISPLAY INVISIBLE (-2275 2125);
FORCEPROP 1 LAST PATH I116
J 0
(-2602 2250);
DISPLAY 0.872340 (-2602 2250);
PAINT GREEN (-2602 2250);
DISPLAY INVISIBLE (-2602 2250);
FORCEADD TAP..1
(-2600 2350);
FORCEPROP 3 LASTPIN (-2650 2350) SIG_NAME P3E_CPU0_PE1_PCH_R_RXN<12>
J 0
(-2640 2360);
DISPLAY 0.659574 (-2640 2360);
PAINT MONO (-2640 2360);
DISPLAY INVISIBLE (-2640 2360);
FORCEPROP 1 LASTPIN (-2650 2350) BN 12
J 0
(-2662 2358);
DISPLAY 0.617021 (-2662 2358);
PAINT GREEN (-2662 2358);
FORCEPROP 2 LAST CDS_LIB mstr_standard
J 0
(-2600 2350);
PAINT ORANGE (-2600 2350);
DISPLAY INVISIBLE (-2600 2350);
FORCEPROP 1 LAST BODY_TYPE PLUMBING
J 0
(-2600 2400);
DISPLAY 1.170213 (-2600 2400);
PAINT GREEN (-2600 2400);
DISPLAY INVISIBLE (-2600 2400);
FORCEPROP 1 LAST HDL_TAP TRUE
J 0
(-2275 2225);
DISPLAY 1.170213 (-2275 2225);
PAINT ORANGE (-2275 2225);
DISPLAY INVISIBLE (-2275 2225);
FORCEPROP 1 LAST PATH I117
J 0
(-2602 2350);
DISPLAY 0.872340 (-2602 2350);
PAINT GREEN (-2602 2350);
DISPLAY INVISIBLE (-2602 2350);
FORCEADD TAP..1
(-2600 2450);
FORCEPROP 3 LASTPIN (-2650 2450) SIG_NAME P3E_CPU0_PE1_PCH_R_RXN<13>
J 0
(-2640 2460);
DISPLAY 0.659574 (-2640 2460);
PAINT MONO (-2640 2460);
DISPLAY INVISIBLE (-2640 2460);
FORCEPROP 1 LASTPIN (-2650 2450) BN 13
J 0
(-2662 2458);
DISPLAY 0.617021 (-2662 2458);
PAINT GREEN (-2662 2458);
FORCEPROP 2 LAST CDS_LIB mstr_standard
J 0
(-2600 2450);
PAINT ORANGE (-2600 2450);
DISPLAY INVISIBLE (-2600 2450);
FORCEPROP 1 LAST BODY_TYPE PLUMBING
J 0
(-2600 2500);
DISPLAY 1.170213 (-2600 2500);
PAINT GREEN (-2600 2500);
DISPLAY INVISIBLE (-2600 2500);
FORCEPROP 1 LAST HDL_TAP TRUE
J 0
(-2275 2325);
DISPLAY 1.170213 (-2275 2325);
PAINT ORANGE (-2275 2325);
DISPLAY INVISIBLE (-2275 2325);
FORCEPROP 1 LAST PATH I118
J 0
(-2602 2450);
DISPLAY 0.872340 (-2602 2450);
PAINT GREEN (-2602 2450);
DISPLAY INVISIBLE (-2602 2450);
FORCEADD TAP..1
(-2600 2550);
FORCEPROP 3 LASTPIN (-2650 2550) SIG_NAME P3E_CPU0_PE1_PCH_R_RXN<14>
J 0
(-2640 2560);
DISPLAY 0.659574 (-2640 2560);
PAINT MONO (-2640 2560);
DISPLAY INVISIBLE (-2640 2560);
FORCEPROP 1 LASTPIN (-2650 2550) BN 14
J 0
(-2662 2558);
DISPLAY 0.617021 (-2662 2558);
PAINT GREEN (-2662 2558);
FORCEPROP 2 LAST CDS_LIB mstr_standard
J 0
(-2600 2550);
PAINT ORANGE (-2600 2550);
DISPLAY INVISIBLE (-2600 2550);
FORCEPROP 1 LAST BODY_TYPE PLUMBING
J 0
(-2600 2600);
DISPLAY 1.170213 (-2600 2600);
PAINT GREEN (-2600 2600);
DISPLAY INVISIBLE (-2600 2600);
FORCEPROP 1 LAST HDL_TAP TRUE
J 0
(-2275 2425);
DISPLAY 1.170213 (-2275 2425);
PAINT ORANGE (-2275 2425);
DISPLAY INVISIBLE (-2275 2425);
FORCEPROP 1 LAST PATH I119
J 0
(-2602 2550);
DISPLAY 0.872340 (-2602 2550);
PAINT GREEN (-2602 2550);
DISPLAY INVISIBLE (-2602 2550);
FORCEADD TAP..1
(-2600 2650);
FORCEPROP 3 LASTPIN (-2650 2650) SIG_NAME P3E_CPU0_PE1_PCH_R_RXN<15>
J 0
(-2640 2660);
DISPLAY 0.659574 (-2640 2660);
PAINT MONO (-2640 2660);
DISPLAY INVISIBLE (-2640 2660);
FORCEPROP 1 LASTPIN (-2650 2650) BN 15
J 0
(-2662 2658);
DISPLAY 0.617021 (-2662 2658);
PAINT GREEN (-2662 2658);
FORCEPROP 2 LAST CDS_LIB mstr_standard
J 0
(-2600 2650);
PAINT ORANGE (-2600 2650);
DISPLAY INVISIBLE (-2600 2650);
FORCEPROP 1 LAST BODY_TYPE PLUMBING
J 0
(-2600 2700);
DISPLAY 1.170213 (-2600 2700);
PAINT GREEN (-2600 2700);
DISPLAY INVISIBLE (-2600 2700);
FORCEPROP 1 LAST HDL_TAP TRUE
J 0
(-2275 2525);
DISPLAY 1.170213 (-2275 2525);
PAINT ORANGE (-2275 2525);
DISPLAY INVISIBLE (-2275 2525);
FORCEPROP 1 LAST PATH I120
J 0
(-2602 2650);
DISPLAY 0.872340 (-2602 2650);
PAINT GREEN (-2602 2650);
DISPLAY INVISIBLE (-2602 2650);
FORCEADD TAP..1
(-2725 2000);
FORCEPROP 3 LASTPIN (-2775 2000) SIG_NAME P3E_CPU0_PE1_PCH_R_RXP<8>
J 0
(-2765 2010);
DISPLAY 0.659574 (-2765 2010);
PAINT MONO (-2765 2010);
DISPLAY INVISIBLE (-2765 2010);
FORCEPROP 1 LASTPIN (-2775 2000) BN 8
J 0
(-2787 2008);
DISPLAY 0.617021 (-2787 2008);
PAINT GREEN (-2787 2008);
FORCEPROP 2 LAST CDS_LIB mstr_standard
J 0
(-2725 2000);
PAINT ORANGE (-2725 2000);
DISPLAY INVISIBLE (-2725 2000);
FORCEPROP 1 LAST BODY_TYPE PLUMBING
J 0
(-2725 2050);
DISPLAY 1.170213 (-2725 2050);
PAINT GREEN (-2725 2050);
DISPLAY INVISIBLE (-2725 2050);
FORCEPROP 1 LAST HDL_TAP TRUE
J 0
(-2400 1875);
DISPLAY 1.170213 (-2400 1875);
PAINT ORANGE (-2400 1875);
DISPLAY INVISIBLE (-2400 1875);
FORCEPROP 1 LAST PATH I121
J 0
(-2727 2000);
DISPLAY 0.872340 (-2727 2000);
PAINT GREEN (-2727 2000);
DISPLAY INVISIBLE (-2727 2000);
FORCEADD TAP..1
(-2725 2100);
FORCEPROP 3 LASTPIN (-2775 2100) SIG_NAME P3E_CPU0_PE1_PCH_R_RXP<9>
J 0
(-2765 2110);
DISPLAY 0.659574 (-2765 2110);
PAINT MONO (-2765 2110);
DISPLAY INVISIBLE (-2765 2110);
FORCEPROP 1 LASTPIN (-2775 2100) BN 9
J 0
(-2787 2108);
DISPLAY 0.617021 (-2787 2108);
PAINT GREEN (-2787 2108);
FORCEPROP 2 LAST CDS_LIB mstr_standard
J 0
(-2725 2100);
PAINT ORANGE (-2725 2100);
DISPLAY INVISIBLE (-2725 2100);
FORCEPROP 1 LAST BODY_TYPE PLUMBING
J 0
(-2725 2150);
DISPLAY 1.170213 (-2725 2150);
PAINT GREEN (-2725 2150);
DISPLAY INVISIBLE (-2725 2150);
FORCEPROP 1 LAST HDL_TAP TRUE
J 0
(-2400 1975);
DISPLAY 1.170213 (-2400 1975);
PAINT ORANGE (-2400 1975);
DISPLAY INVISIBLE (-2400 1975);
FORCEPROP 1 LAST PATH I122
J 0
(-2727 2100);
DISPLAY 0.872340 (-2727 2100);
PAINT GREEN (-2727 2100);
DISPLAY INVISIBLE (-2727 2100);
FORCEADD TAP..1
(-2725 2200);
FORCEPROP 3 LASTPIN (-2775 2200) SIG_NAME P3E_CPU0_PE1_PCH_R_RXP<10>
J 0
(-2765 2210);
DISPLAY 0.659574 (-2765 2210);
PAINT MONO (-2765 2210);
DISPLAY INVISIBLE (-2765 2210);
FORCEPROP 1 LASTPIN (-2775 2200) BN 10
J 0
(-2787 2208);
DISPLAY 0.617021 (-2787 2208);
PAINT GREEN (-2787 2208);
FORCEPROP 2 LAST CDS_LIB mstr_standard
J 0
(-2725 2200);
PAINT ORANGE (-2725 2200);
DISPLAY INVISIBLE (-2725 2200);
FORCEPROP 1 LAST BODY_TYPE PLUMBING
J 0
(-2725 2250);
DISPLAY 1.170213 (-2725 2250);
PAINT GREEN (-2725 2250);
DISPLAY INVISIBLE (-2725 2250);
FORCEPROP 1 LAST HDL_TAP TRUE
J 0
(-2400 2075);
DISPLAY 1.170213 (-2400 2075);
PAINT ORANGE (-2400 2075);
DISPLAY INVISIBLE (-2400 2075);
FORCEPROP 1 LAST PATH I123
J 0
(-2727 2200);
DISPLAY 0.872340 (-2727 2200);
PAINT GREEN (-2727 2200);
DISPLAY INVISIBLE (-2727 2200);
FORCEADD TAP..1
(-2725 2300);
FORCEPROP 3 LASTPIN (-2775 2300) SIG_NAME P3E_CPU0_PE1_PCH_R_RXP<11>
J 0
(-2765 2310);
DISPLAY 0.659574 (-2765 2310);
PAINT MONO (-2765 2310);
DISPLAY INVISIBLE (-2765 2310);
FORCEPROP 1 LASTPIN (-2775 2300) BN 11
J 0
(-2787 2308);
DISPLAY 0.617021 (-2787 2308);
PAINT GREEN (-2787 2308);
FORCEPROP 2 LAST CDS_LIB mstr_standard
J 0
(-2725 2300);
PAINT ORANGE (-2725 2300);
DISPLAY INVISIBLE (-2725 2300);
FORCEPROP 1 LAST BODY_TYPE PLUMBING
J 0
(-2725 2350);
DISPLAY 1.170213 (-2725 2350);
PAINT GREEN (-2725 2350);
DISPLAY INVISIBLE (-2725 2350);
FORCEPROP 1 LAST HDL_TAP TRUE
J 0
(-2400 2175);
DISPLAY 1.170213 (-2400 2175);
PAINT ORANGE (-2400 2175);
DISPLAY INVISIBLE (-2400 2175);
FORCEPROP 1 LAST PATH I124
J 0
(-2727 2300);
DISPLAY 0.872340 (-2727 2300);
PAINT GREEN (-2727 2300);
DISPLAY INVISIBLE (-2727 2300);
FORCEADD TAP..1
(-2725 2400);
FORCEPROP 3 LASTPIN (-2775 2400) SIG_NAME P3E_CPU0_PE1_PCH_R_RXP<12>
J 0
(-2765 2410);
DISPLAY 0.659574 (-2765 2410);
PAINT MONO (-2765 2410);
DISPLAY INVISIBLE (-2765 2410);
FORCEPROP 1 LASTPIN (-2775 2400) BN 12
J 0
(-2787 2408);
DISPLAY 0.617021 (-2787 2408);
PAINT GREEN (-2787 2408);
FORCEPROP 2 LAST CDS_LIB mstr_standard
J 0
(-2725 2400);
PAINT ORANGE (-2725 2400);
DISPLAY INVISIBLE (-2725 2400);
FORCEPROP 1 LAST BODY_TYPE PLUMBING
J 0
(-2725 2450);
DISPLAY 1.170213 (-2725 2450);
PAINT GREEN (-2725 2450);
DISPLAY INVISIBLE (-2725 2450);
FORCEPROP 1 LAST HDL_TAP TRUE
J 0
(-2400 2275);
DISPLAY 1.170213 (-2400 2275);
PAINT ORANGE (-2400 2275);
DISPLAY INVISIBLE (-2400 2275);
FORCEPROP 1 LAST PATH I125
J 0
(-2727 2400);
DISPLAY 0.872340 (-2727 2400);
PAINT GREEN (-2727 2400);
DISPLAY INVISIBLE (-2727 2400);
FORCEADD TAP..1
(-2725 2500);
FORCEPROP 3 LASTPIN (-2775 2500) SIG_NAME P3E_CPU0_PE1_PCH_R_RXP<13>
J 0
(-2765 2510);
DISPLAY 0.659574 (-2765 2510);
PAINT MONO (-2765 2510);
DISPLAY INVISIBLE (-2765 2510);
FORCEPROP 1 LASTPIN (-2775 2500) BN 13
J 0
(-2787 2508);
DISPLAY 0.617021 (-2787 2508);
PAINT GREEN (-2787 2508);
FORCEPROP 2 LAST CDS_LIB mstr_standard
J 0
(-2725 2500);
PAINT ORANGE (-2725 2500);
DISPLAY INVISIBLE (-2725 2500);
FORCEPROP 1 LAST BODY_TYPE PLUMBING
J 0
(-2725 2550);
DISPLAY 1.170213 (-2725 2550);
PAINT GREEN (-2725 2550);
DISPLAY INVISIBLE (-2725 2550);
FORCEPROP 1 LAST HDL_TAP TRUE
J 0
(-2400 2375);
DISPLAY 1.170213 (-2400 2375);
PAINT ORANGE (-2400 2375);
DISPLAY INVISIBLE (-2400 2375);
FORCEPROP 1 LAST PATH I126
J 0
(-2727 2500);
DISPLAY 0.872340 (-2727 2500);
PAINT GREEN (-2727 2500);
DISPLAY INVISIBLE (-2727 2500);
FORCEADD TAP..1
(-2725 2600);
FORCEPROP 3 LASTPIN (-2775 2600) SIG_NAME P3E_CPU0_PE1_PCH_R_RXP<14>
J 0
(-2765 2610);
DISPLAY 0.659574 (-2765 2610);
PAINT MONO (-2765 2610);
DISPLAY INVISIBLE (-2765 2610);
FORCEPROP 1 LASTPIN (-2775 2600) BN 14
J 0
(-2787 2608);
DISPLAY 0.617021 (-2787 2608);
PAINT GREEN (-2787 2608);
FORCEPROP 2 LAST CDS_LIB mstr_standard
J 0
(-2725 2600);
PAINT ORANGE (-2725 2600);
DISPLAY INVISIBLE (-2725 2600);
FORCEPROP 1 LAST BODY_TYPE PLUMBING
J 0
(-2725 2650);
DISPLAY 1.170213 (-2725 2650);
PAINT GREEN (-2725 2650);
DISPLAY INVISIBLE (-2725 2650);
FORCEPROP 1 LAST HDL_TAP TRUE
J 0
(-2400 2475);
DISPLAY 1.170213 (-2400 2475);
PAINT ORANGE (-2400 2475);
DISPLAY INVISIBLE (-2400 2475);
FORCEPROP 1 LAST PATH I127
J 0
(-2727 2600);
DISPLAY 0.872340 (-2727 2600);
PAINT GREEN (-2727 2600);
DISPLAY INVISIBLE (-2727 2600);
FORCEADD TAP..1
(-2725 2700);
FORCEPROP 3 LASTPIN (-2775 2700) SIG_NAME P3E_CPU0_PE1_PCH_R_RXP<15>
J 0
(-2765 2710);
DISPLAY 0.659574 (-2765 2710);
PAINT MONO (-2765 2710);
DISPLAY INVISIBLE (-2765 2710);
FORCEPROP 1 LASTPIN (-2775 2700) BN 15
J 0
(-2787 2708);
DISPLAY 0.617021 (-2787 2708);
PAINT GREEN (-2787 2708);
FORCEPROP 2 LAST CDS_LIB mstr_standard
J 0
(-2725 2700);
PAINT ORANGE (-2725 2700);
DISPLAY INVISIBLE (-2725 2700);
FORCEPROP 1 LAST BODY_TYPE PLUMBING
J 0
(-2725 2750);
DISPLAY 1.170213 (-2725 2750);
PAINT GREEN (-2725 2750);
DISPLAY INVISIBLE (-2725 2750);
FORCEPROP 1 LAST HDL_TAP TRUE
J 0
(-2400 2575);
DISPLAY 1.170213 (-2400 2575);
PAINT ORANGE (-2400 2575);
DISPLAY INVISIBLE (-2400 2575);
FORCEPROP 1 LAST PATH I128
J 0
(-2727 2700);
DISPLAY 0.872340 (-2727 2700);
PAINT GREEN (-2727 2700);
DISPLAY INVISIBLE (-2727 2700);
FORCEADD OFFPAGE..1
(-6700 2025);
FORCEPROP 2 LAST $XR0 105 
J 0
(-6952 2025);
DISPLAY 0.638298 (-6952 2025);
PAINT MONO (-6952 2025);
FORCEPROP 2 LAST CDS_LIB mstr_standard
J 0
(-6700 2025);
PAINT ORANGE (-6700 2025);
DISPLAY INVISIBLE (-6700 2025);
FORCEPROP 1 LAST OFFPAGE TRUE
J 0
(-6375 1900);
DISPLAY 0.872340 (-6375 1900);
PAINT GREEN (-6375 1900);
DISPLAY INVISIBLE (-6375 1900);
FORCEPROP 1 LAST COMMENT_BODY TRUE
J 0
(-6575 1925);
DISPLAY 0.872340 (-6575 1925);
PAINT GREEN (-6575 1925);
DISPLAY INVISIBLE (-6575 1925);
FORCEPROP 2 LAST PATH I129
J 0
(-6650 2100);
DISPLAY 1.021277 (-6650 2100);
PAINT ORANGE (-6650 2100);
DISPLAY INVISIBLE (-6650 2100);
FORCEADD OFFPAGE..1
(-6700 1925);
FORCEPROP 2 LAST $XR0 105 
J 0
(-6952 1925);
DISPLAY 0.638298 (-6952 1925);
PAINT MONO (-6952 1925);
FORCEPROP 2 LAST CDS_LIB mstr_standard
J 0
(-6700 1925);
PAINT ORANGE (-6700 1925);
DISPLAY INVISIBLE (-6700 1925);
FORCEPROP 1 LAST OFFPAGE TRUE
J 0
(-6375 1800);
DISPLAY 0.872340 (-6375 1800);
PAINT GREEN (-6375 1800);
DISPLAY INVISIBLE (-6375 1800);
FORCEPROP 1 LAST COMMENT_BODY TRUE
J 0
(-6575 1825);
DISPLAY 0.872340 (-6575 1825);
PAINT GREEN (-6575 1825);
DISPLAY INVISIBLE (-6575 1825);
FORCEPROP 2 LAST PATH I130
J 0
(-6650 2000);
DISPLAY 1.021277 (-6650 2000);
PAINT ORANGE (-6650 2000);
DISPLAY INVISIBLE (-6650 2000);
FORCEADD OFFPAGE..2
(-1375 2025);
FORCEPROP 2 LAST $XR0 105 
J 0
(-1186 2025);
DISPLAY 0.638298 (-1186 2025);
PAINT MONO (-1186 2025);
FORCEPROP 2 LAST CDS_LIB mstr_standard
J 0
(-1375 2025);
PAINT ORANGE (-1375 2025);
DISPLAY INVISIBLE (-1375 2025);
FORCEPROP 1 LAST OFFPAGE TRUE
J 0
(-1050 1900);
DISPLAY 0.872340 (-1050 1900);
PAINT GREEN (-1050 1900);
DISPLAY INVISIBLE (-1050 1900);
FORCEPROP 1 LAST COMMENT_BODY TRUE
J 0
(-1420 1930);
DISPLAY 0.872340 (-1420 1930);
PAINT GREEN (-1420 1930);
DISPLAY INVISIBLE (-1420 1930);
FORCEPROP 2 LAST PATH I131
J 0
(-1200 2100);
DISPLAY 1.021277 (-1200 2100);
PAINT ORANGE (-1200 2100);
DISPLAY INVISIBLE (-1200 2100);
FORCEADD OFFPAGE..2
(-1350 1950);
FORCEPROP 2 LAST $XR0 105 
J 0
(-1161 1950);
DISPLAY 0.638298 (-1161 1950);
PAINT MONO (-1161 1950);
FORCEPROP 2 LAST CDS_LIB mstr_standard
J 0
(-1350 1950);
PAINT ORANGE (-1350 1950);
DISPLAY INVISIBLE (-1350 1950);
FORCEPROP 1 LAST OFFPAGE TRUE
J 0
(-1025 1825);
DISPLAY 0.872340 (-1025 1825);
PAINT GREEN (-1025 1825);
DISPLAY INVISIBLE (-1025 1825);
FORCEPROP 1 LAST COMMENT_BODY TRUE
J 0
(-1395 1855);
DISPLAY 0.872340 (-1395 1855);
PAINT GREEN (-1395 1855);
DISPLAY INVISIBLE (-1395 1855);
FORCEPROP 2 LAST PATH I132
J 0
(-1175 2025);
DISPLAY 1.021277 (-1175 2025);
PAINT ORANGE (-1175 2025);
DISPLAY INVISIBLE (-1175 2025);
FORCEADD TAP..6
(-5625 2300);
FORCEPROP 3 LASTPIN (-5575 2300) SIG_NAME P3E_CPU0_PE1_PCH_C_TXP<11>
J 0
(-5565 2310);
DISPLAY 0.659574 (-5565 2310);
PAINT MONO (-5565 2310);
DISPLAY INVISIBLE (-5565 2310);
FORCEPROP 1 LASTPIN (-5575 2300) BN 11
J 0
(-5627 2308);
DISPLAY 0.617021 (-5627 2308);
PAINT GREEN (-5627 2308);
FORCEPROP 2 LAST CDS_LIB mstr_standard
J 0
(-5625 2300);
PAINT ORANGE (-5625 2300);
DISPLAY INVISIBLE (-5625 2300);
FORCEPROP 1 LAST BODY_TYPE PLUMBING
J 0
(-5625 2250);
DISPLAY 1.170213 (-5625 2250);
PAINT GREEN (-5625 2250);
DISPLAY INVISIBLE (-5625 2250);
FORCEPROP 1 LAST HDL_TAP TRUE
J 0
(-5300 2175);
DISPLAY 1.170213 (-5300 2175);
PAINT ORANGE (-5300 2175);
DISPLAY INVISIBLE (-5300 2175);
FORCEPROP 1 LAST PATH I133
J 0
(-5627 2300);
DISPLAY 0.872340 (-5627 2300);
PAINT GREEN (-5627 2300);
DISPLAY INVISIBLE (-5627 2300);
FORCEADD TAP..6
(-5500 2250);
FORCEPROP 3 LASTPIN (-5450 2250) SIG_NAME P3E_CPU0_PE1_PCH_C_TXN<11>
J 0
(-5440 2260);
DISPLAY 0.659574 (-5440 2260);
PAINT MONO (-5440 2260);
DISPLAY INVISIBLE (-5440 2260);
FORCEPROP 1 LASTPIN (-5450 2250) BN 11
J 0
(-5502 2258);
DISPLAY 0.617021 (-5502 2258);
PAINT GREEN (-5502 2258);
FORCEPROP 2 LAST CDS_LIB mstr_standard
J 0
(-5500 2250);
PAINT ORANGE (-5500 2250);
DISPLAY INVISIBLE (-5500 2250);
FORCEPROP 1 LAST BODY_TYPE PLUMBING
J 0
(-5500 2200);
DISPLAY 1.170213 (-5500 2200);
PAINT GREEN (-5500 2200);
DISPLAY INVISIBLE (-5500 2200);
FORCEPROP 1 LAST HDL_TAP TRUE
J 0
(-5175 2125);
DISPLAY 1.170213 (-5175 2125);
PAINT ORANGE (-5175 2125);
DISPLAY INVISIBLE (-5175 2125);
FORCEPROP 1 LAST PATH I134
J 0
(-5502 2250);
DISPLAY 0.872340 (-5502 2250);
PAINT GREEN (-5502 2250);
DISPLAY INVISIBLE (-5502 2250);
FORCEADD OFFPAGE..1
(-6500 3350);
FORCEPROP 2 LAST $XR0 129 
J 0
(-6752 3350);
DISPLAY 0.638298 (-6752 3350);
PAINT MONO (-6752 3350);
FORCEPROP 2 LAST CDS_LIB mstr_standard
J 0
(-6500 3350);
PAINT ORANGE (-6500 3350);
DISPLAY INVISIBLE (-6500 3350);
FORCEPROP 1 LAST OFFPAGE TRUE
J 0
(-6175 3225);
DISPLAY 1.170213 (-6175 3225);
PAINT GREEN (-6175 3225);
DISPLAY INVISIBLE (-6175 3225);
FORCEPROP 1 LAST COMMENT_BODY TRUE
J 0
(-6375 3250);
DISPLAY 1.170213 (-6375 3250);
PAINT PEACH (-6375 3250);
DISPLAY INVISIBLE (-6375 3250);
FORCEPROP 2 LAST PATH I18
J 0
(-6450 3425);
DISPLAY 1.021277 (-6450 3425);
PAINT ORANGE (-6450 3425);
DISPLAY INVISIBLE (-6450 3425);
FORCEADD OFFPAGE..1
(-6500 3250);
FORCEPROP 2 LAST $XR0 129 
J 0
(-6752 3250);
DISPLAY 0.638298 (-6752 3250);
PAINT MONO (-6752 3250);
FORCEPROP 2 LAST CDS_LIB mstr_standard
J 0
(-6500 3250);
PAINT ORANGE (-6500 3250);
DISPLAY INVISIBLE (-6500 3250);
FORCEPROP 1 LAST OFFPAGE TRUE
J 0
(-6175 3125);
DISPLAY 1.170213 (-6175 3125);
PAINT GREEN (-6175 3125);
DISPLAY INVISIBLE (-6175 3125);
FORCEPROP 1 LAST COMMENT_BODY TRUE
J 0
(-6375 3150);
DISPLAY 1.170213 (-6375 3150);
PAINT PEACH (-6375 3150);
DISPLAY INVISIBLE (-6375 3150);
FORCEPROP 2 LAST PATH I19
J 0
(-6450 3325);
DISPLAY 1.021277 (-6450 3325);
PAINT ORANGE (-6450 3325);
DISPLAY INVISIBLE (-6450 3325);
FORCEADD TAP..1
R 2
(-5425 3150);
FORCEPROP 3 LASTPIN (-5375 3150) SIG_NAME DMI_CPU0_PCH_TX_C_DP<3>
J 0
(-5365 3160);
DISPLAY 0.659574 (-5365 3160);
PAINT MONO (-5365 3160);
DISPLAY INVISIBLE (-5365 3160);
FORCEPROP 1 LASTPIN (-5375 3150) BN 3
J 2
(-5363 3158);
DISPLAY 0.617021 (-5363 3158);
PAINT VIOLET (-5363 3158);
FORCEPROP 2 LAST BOM_COST SB
J 0
(-5450 3200);
DISPLAY 0.744681 (-5450 3200);
PAINT MONO (-5450 3200);
DISPLAY INVISIBLE (-5450 3200);
FORCEPROP 2 LAST CDS_LIB mstr_standard
J 0
(-5425 3150);
PAINT ORANGE (-5425 3150);
DISPLAY INVISIBLE (-5425 3150);
FORCEPROP 1 LAST BODY_TYPE PLUMBING
J 2
(-5425 3200);
DISPLAY 1.085106 (-5425 3200);
PAINT GREEN (-5425 3200);
DISPLAY INVISIBLE (-5425 3200);
FORCEPROP 1 LAST HDL_TAP TRUE
J 2
(-5750 3025);
DISPLAY 1.085106 (-5750 3025);
PAINT GREEN (-5750 3025);
DISPLAY INVISIBLE (-5750 3025);
FORCEPROP 1 LAST PATH I21
J 2
(-5423 3150);
DISPLAY 0.872340 (-5423 3150);
PAINT GREEN (-5423 3150);
DISPLAY INVISIBLE (-5423 3150);
FORCEADD TAP..1
R 2
(-5425 3050);
FORCEPROP 3 LASTPIN (-5375 3050) SIG_NAME DMI_CPU0_PCH_TX_C_DP<2>
J 0
(-5365 3060);
DISPLAY 0.659574 (-5365 3060);
PAINT MONO (-5365 3060);
DISPLAY INVISIBLE (-5365 3060);
FORCEPROP 1 LASTPIN (-5375 3050) BN 2
J 2
(-5363 3058);
DISPLAY 0.617021 (-5363 3058);
PAINT VIOLET (-5363 3058);
FORCEPROP 2 LAST BOM_COST SB
J 0
(-5450 3100);
DISPLAY 0.744681 (-5450 3100);
PAINT MONO (-5450 3100);
DISPLAY INVISIBLE (-5450 3100);
FORCEPROP 2 LAST CDS_LIB mstr_standard
J 0
(-5425 3050);
PAINT ORANGE (-5425 3050);
DISPLAY INVISIBLE (-5425 3050);
FORCEPROP 1 LAST BODY_TYPE PLUMBING
J 2
(-5425 3100);
DISPLAY 1.085106 (-5425 3100);
PAINT GREEN (-5425 3100);
DISPLAY INVISIBLE (-5425 3100);
FORCEPROP 1 LAST HDL_TAP TRUE
J 2
(-5750 2925);
DISPLAY 1.085106 (-5750 2925);
PAINT GREEN (-5750 2925);
DISPLAY INVISIBLE (-5750 2925);
FORCEPROP 1 LAST PATH I22
J 2
(-5423 3050);
DISPLAY 0.872340 (-5423 3050);
PAINT GREEN (-5423 3050);
DISPLAY INVISIBLE (-5423 3050);
FORCEADD TAP..1
R 2
(-5425 2950);
FORCEPROP 3 LASTPIN (-5375 2950) SIG_NAME DMI_CPU0_PCH_TX_C_DP<1>
J 0
(-5365 2960);
DISPLAY 0.659574 (-5365 2960);
PAINT MONO (-5365 2960);
DISPLAY INVISIBLE (-5365 2960);
FORCEPROP 1 LASTPIN (-5375 2950) BN 1
J 2
(-5363 2958);
DISPLAY 0.617021 (-5363 2958);
PAINT VIOLET (-5363 2958);
FORCEPROP 2 LAST CDS_LIB mstr_standard
J 0
(-5425 2950);
PAINT ORANGE (-5425 2950);
DISPLAY INVISIBLE (-5425 2950);
FORCEPROP 2 LAST BOM_COST SB
J 0
(-5450 3000);
DISPLAY 0.744681 (-5450 3000);
PAINT MONO (-5450 3000);
DISPLAY INVISIBLE (-5450 3000);
FORCEPROP 1 LAST BODY_TYPE PLUMBING
J 2
(-5425 3000);
DISPLAY 1.085106 (-5425 3000);
PAINT GREEN (-5425 3000);
DISPLAY INVISIBLE (-5425 3000);
FORCEPROP 1 LAST HDL_TAP TRUE
J 2
(-5750 2825);
DISPLAY 1.085106 (-5750 2825);
PAINT GREEN (-5750 2825);
DISPLAY INVISIBLE (-5750 2825);
FORCEPROP 1 LAST PATH I23
J 2
(-5423 2950);
DISPLAY 0.872340 (-5423 2950);
PAINT GREEN (-5423 2950);
DISPLAY INVISIBLE (-5423 2950);
FORCEADD TAP..1
R 2
(-5425 2850);
FORCEPROP 3 LASTPIN (-5375 2850) SIG_NAME DMI_CPU0_PCH_TX_C_DP<0>
J 0
(-5365 2860);
DISPLAY 0.659574 (-5365 2860);
PAINT MONO (-5365 2860);
DISPLAY INVISIBLE (-5365 2860);
FORCEPROP 1 LASTPIN (-5375 2850) BN 0
J 2
(-5363 2858);
DISPLAY 0.617021 (-5363 2858);
PAINT VIOLET (-5363 2858);
FORCEPROP 2 LAST CDS_LIB mstr_standard
J 0
(-5425 2850);
PAINT ORANGE (-5425 2850);
DISPLAY INVISIBLE (-5425 2850);
FORCEPROP 2 LAST BOM_COST SB
J 0
(-5450 2900);
DISPLAY 0.744681 (-5450 2900);
PAINT MONO (-5450 2900);
DISPLAY INVISIBLE (-5450 2900);
FORCEPROP 1 LAST BODY_TYPE PLUMBING
J 2
(-5425 2900);
DISPLAY 1.085106 (-5425 2900);
PAINT GREEN (-5425 2900);
DISPLAY INVISIBLE (-5425 2900);
FORCEPROP 1 LAST HDL_TAP TRUE
J 2
(-5750 2725);
DISPLAY 1.085106 (-5750 2725);
PAINT GREEN (-5750 2725);
DISPLAY INVISIBLE (-5750 2725);
FORCEPROP 1 LAST PATH I24
J 2
(-5423 2850);
DISPLAY 0.872340 (-5423 2850);
PAINT GREEN (-5423 2850);
DISPLAY INVISIBLE (-5423 2850);
FORCEADD TAP..1
R 2
(-5575 3100);
FORCEPROP 3 LASTPIN (-5525 3100) SIG_NAME DMI_CPU0_PCH_TX_C_DN<3>
J 0
(-5515 3110);
DISPLAY 0.659574 (-5515 3110);
PAINT MONO (-5515 3110);
DISPLAY INVISIBLE (-5515 3110);
FORCEPROP 1 LASTPIN (-5525 3100) BN 3
J 2
(-5513 3108);
DISPLAY 0.617021 (-5513 3108);
PAINT VIOLET (-5513 3108);
FORCEPROP 2 LAST BOM_COST SB
J 0
(-5600 3150);
DISPLAY 0.744681 (-5600 3150);
PAINT MONO (-5600 3150);
DISPLAY INVISIBLE (-5600 3150);
FORCEPROP 2 LAST CDS_LIB mstr_standard
J 0
(-5575 3100);
PAINT ORANGE (-5575 3100);
DISPLAY INVISIBLE (-5575 3100);
FORCEPROP 1 LAST BODY_TYPE PLUMBING
J 2
(-5575 3150);
DISPLAY 1.085106 (-5575 3150);
PAINT GREEN (-5575 3150);
DISPLAY INVISIBLE (-5575 3150);
FORCEPROP 1 LAST HDL_TAP TRUE
J 2
(-5900 2975);
DISPLAY 1.085106 (-5900 2975);
PAINT GREEN (-5900 2975);
DISPLAY INVISIBLE (-5900 2975);
FORCEPROP 1 LAST PATH I25
J 2
(-5573 3100);
DISPLAY 0.872340 (-5573 3100);
PAINT GREEN (-5573 3100);
DISPLAY INVISIBLE (-5573 3100);
FORCEADD TAP..1
R 2
(-5575 3000);
FORCEPROP 3 LASTPIN (-5525 3000) SIG_NAME DMI_CPU0_PCH_TX_C_DN<2>
J 0
(-5515 3010);
DISPLAY 0.659574 (-5515 3010);
PAINT MONO (-5515 3010);
DISPLAY INVISIBLE (-5515 3010);
FORCEPROP 1 LASTPIN (-5525 3000) BN 2
J 2
(-5513 3008);
DISPLAY 0.617021 (-5513 3008);
PAINT VIOLET (-5513 3008);
FORCEPROP 2 LAST BOM_COST SB
J 0
(-5600 3050);
DISPLAY 0.744681 (-5600 3050);
PAINT MONO (-5600 3050);
DISPLAY INVISIBLE (-5600 3050);
FORCEPROP 2 LAST CDS_LIB mstr_standard
J 0
(-5575 3000);
PAINT ORANGE (-5575 3000);
DISPLAY INVISIBLE (-5575 3000);
FORCEPROP 1 LAST BODY_TYPE PLUMBING
J 2
(-5575 3050);
DISPLAY 1.085106 (-5575 3050);
PAINT GREEN (-5575 3050);
DISPLAY INVISIBLE (-5575 3050);
FORCEPROP 1 LAST HDL_TAP TRUE
J 2
(-5900 2875);
DISPLAY 1.085106 (-5900 2875);
PAINT GREEN (-5900 2875);
DISPLAY INVISIBLE (-5900 2875);
FORCEPROP 1 LAST PATH I26
J 2
(-5573 3000);
DISPLAY 0.872340 (-5573 3000);
PAINT GREEN (-5573 3000);
DISPLAY INVISIBLE (-5573 3000);
FORCEADD TAP..1
R 2
(-5575 2900);
FORCEPROP 3 LASTPIN (-5525 2900) SIG_NAME DMI_CPU0_PCH_TX_C_DN<1>
J 0
(-5515 2910);
DISPLAY 0.659574 (-5515 2910);
PAINT MONO (-5515 2910);
DISPLAY INVISIBLE (-5515 2910);
FORCEPROP 1 LASTPIN (-5525 2900) BN 1
J 2
(-5513 2908);
DISPLAY 0.617021 (-5513 2908);
PAINT VIOLET (-5513 2908);
FORCEPROP 2 LAST BOM_COST SB
J 0
(-5600 2950);
DISPLAY 0.744681 (-5600 2950);
PAINT MONO (-5600 2950);
DISPLAY INVISIBLE (-5600 2950);
FORCEPROP 2 LAST CDS_LIB mstr_standard
J 0
(-5575 2900);
PAINT ORANGE (-5575 2900);
DISPLAY INVISIBLE (-5575 2900);
FORCEPROP 1 LAST BODY_TYPE PLUMBING
J 2
(-5575 2950);
DISPLAY 1.085106 (-5575 2950);
PAINT GREEN (-5575 2950);
DISPLAY INVISIBLE (-5575 2950);
FORCEPROP 1 LAST HDL_TAP TRUE
J 2
(-5900 2775);
DISPLAY 1.085106 (-5900 2775);
PAINT GREEN (-5900 2775);
DISPLAY INVISIBLE (-5900 2775);
FORCEPROP 1 LAST PATH I27
J 2
(-5573 2900);
DISPLAY 0.872340 (-5573 2900);
PAINT GREEN (-5573 2900);
DISPLAY INVISIBLE (-5573 2900);
FORCEADD TAP..1
R 2
(-5575 2800);
FORCEPROP 3 LASTPIN (-5525 2800) SIG_NAME DMI_CPU0_PCH_TX_C_DN<0>
J 0
(-5515 2810);
DISPLAY 0.659574 (-5515 2810);
PAINT MONO (-5515 2810);
DISPLAY INVISIBLE (-5515 2810);
FORCEPROP 1 LASTPIN (-5525 2800) BN 0
J 2
(-5513 2808);
DISPLAY 0.617021 (-5513 2808);
PAINT VIOLET (-5513 2808);
FORCEPROP 2 LAST BOM_COST SB
J 0
(-5600 2850);
DISPLAY 0.744681 (-5600 2850);
PAINT MONO (-5600 2850);
DISPLAY INVISIBLE (-5600 2850);
FORCEPROP 2 LAST CDS_LIB mstr_standard
J 0
(-5575 2800);
PAINT ORANGE (-5575 2800);
DISPLAY INVISIBLE (-5575 2800);
FORCEPROP 1 LAST BODY_TYPE PLUMBING
J 2
(-5575 2850);
DISPLAY 1.085106 (-5575 2850);
PAINT GREEN (-5575 2850);
DISPLAY INVISIBLE (-5575 2850);
FORCEPROP 1 LAST HDL_TAP TRUE
J 2
(-5900 2675);
DISPLAY 1.085106 (-5900 2675);
PAINT GREEN (-5900 2675);
DISPLAY INVISIBLE (-5900 2675);
FORCEPROP 1 LAST PATH I28
J 2
(-5573 2800);
DISPLAY 0.872340 (-5573 2800);
PAINT GREEN (-5573 2800);
DISPLAY INVISIBLE (-5573 2800);
FORCEADD TAP..6
R 2
(-2725 3150);
FORCEPROP 3 LASTPIN (-2775 3150) SIG_NAME DMI_CPU0_PCH_RX_DP<3>
J 0
(-2765 3160);
DISPLAY 0.659574 (-2765 3160);
PAINT MONO (-2765 3160);
DISPLAY INVISIBLE (-2765 3160);
FORCEPROP 1 LASTPIN (-2775 3150) BN 3
J 2
(-2723 3158);
DISPLAY 0.617021 (-2723 3158);
PAINT VIOLET (-2723 3158);
FORCEPROP 2 LAST BOM_COST SB
J 0
(-2750 3200);
DISPLAY 0.744681 (-2750 3200);
PAINT MONO (-2750 3200);
DISPLAY INVISIBLE (-2750 3200);
FORCEPROP 2 LAST CDS_LIB mstr_standard
J 0
(-2725 3150);
PAINT ORANGE (-2725 3150);
DISPLAY INVISIBLE (-2725 3150);
FORCEPROP 1 LAST BODY_TYPE PLUMBING
J 2
(-2725 3100);
DISPLAY 0.872340 (-2725 3100);
PAINT GREEN (-2725 3100);
DISPLAY INVISIBLE (-2725 3100);
FORCEPROP 1 LAST HDL_TAP TRUE
J 2
(-3050 3025);
DISPLAY 0.872340 (-3050 3025);
PAINT GREEN (-3050 3025);
DISPLAY INVISIBLE (-3050 3025);
FORCEPROP 1 LAST PATH I29
J 2
(-2723 3150);
DISPLAY 0.872340 (-2723 3150);
PAINT GREEN (-2723 3150);
DISPLAY INVISIBLE (-2723 3150);
FORCEADD TAP..6
R 2
(-2600 3100);
FORCEPROP 3 LASTPIN (-2650 3100) SIG_NAME DMI_CPU0_PCH_RX_DN<3>
J 0
(-2640 3110);
DISPLAY 0.659574 (-2640 3110);
PAINT MONO (-2640 3110);
DISPLAY INVISIBLE (-2640 3110);
FORCEPROP 1 LASTPIN (-2650 3100) BN 3
J 2
(-2598 3108);
DISPLAY 0.617021 (-2598 3108);
PAINT VIOLET (-2598 3108);
FORCEPROP 2 LAST BOM_COST SB
J 0
(-2625 3150);
DISPLAY 0.744681 (-2625 3150);
PAINT MONO (-2625 3150);
DISPLAY INVISIBLE (-2625 3150);
FORCEPROP 2 LAST CDS_LIB mstr_standard
J 0
(-2600 3100);
PAINT ORANGE (-2600 3100);
DISPLAY INVISIBLE (-2600 3100);
FORCEPROP 1 LAST BODY_TYPE PLUMBING
J 2
(-2600 3050);
DISPLAY 0.872340 (-2600 3050);
PAINT GREEN (-2600 3050);
DISPLAY INVISIBLE (-2600 3050);
FORCEPROP 1 LAST HDL_TAP TRUE
J 2
(-2925 2975);
DISPLAY 0.872340 (-2925 2975);
PAINT GREEN (-2925 2975);
DISPLAY INVISIBLE (-2925 2975);
FORCEPROP 1 LAST PATH I30
J 2
(-2598 3100);
DISPLAY 0.872340 (-2598 3100);
PAINT GREEN (-2598 3100);
DISPLAY INVISIBLE (-2598 3100);
FORCEADD TAP..6
R 2
(-2725 3050);
FORCEPROP 3 LASTPIN (-2775 3050) SIG_NAME DMI_CPU0_PCH_RX_DP<2>
J 0
(-2765 3060);
DISPLAY 0.659574 (-2765 3060);
PAINT MONO (-2765 3060);
DISPLAY INVISIBLE (-2765 3060);
FORCEPROP 1 LASTPIN (-2775 3050) BN 2
J 2
(-2723 3058);
DISPLAY 0.617021 (-2723 3058);
PAINT VIOLET (-2723 3058);
FORCEPROP 2 LAST BOM_COST SB
J 0
(-2750 3100);
DISPLAY 0.744681 (-2750 3100);
PAINT MONO (-2750 3100);
DISPLAY INVISIBLE (-2750 3100);
FORCEPROP 2 LAST CDS_LIB mstr_standard
J 0
(-2725 3050);
PAINT ORANGE (-2725 3050);
DISPLAY INVISIBLE (-2725 3050);
FORCEPROP 1 LAST BODY_TYPE PLUMBING
J 2
(-2725 3000);
DISPLAY 0.872340 (-2725 3000);
PAINT GREEN (-2725 3000);
DISPLAY INVISIBLE (-2725 3000);
FORCEPROP 1 LAST HDL_TAP TRUE
J 2
(-3050 2925);
DISPLAY 0.872340 (-3050 2925);
PAINT GREEN (-3050 2925);
DISPLAY INVISIBLE (-3050 2925);
FORCEPROP 1 LAST PATH I31
J 2
(-2723 3050);
DISPLAY 0.872340 (-2723 3050);
PAINT GREEN (-2723 3050);
DISPLAY INVISIBLE (-2723 3050);
FORCEADD TAP..6
R 2
(-2725 2950);
FORCEPROP 3 LASTPIN (-2775 2950) SIG_NAME DMI_CPU0_PCH_RX_DP<1>
J 0
(-2765 2960);
DISPLAY 0.659574 (-2765 2960);
PAINT MONO (-2765 2960);
DISPLAY INVISIBLE (-2765 2960);
FORCEPROP 1 LASTPIN (-2775 2950) BN 1
J 2
(-2723 2958);
DISPLAY 0.617021 (-2723 2958);
PAINT VIOLET (-2723 2958);
FORCEPROP 2 LAST BOM_COST SB
J 0
(-2750 3000);
DISPLAY 0.744681 (-2750 3000);
PAINT MONO (-2750 3000);
DISPLAY INVISIBLE (-2750 3000);
FORCEPROP 2 LAST CDS_LIB mstr_standard
J 0
(-2725 2950);
PAINT ORANGE (-2725 2950);
DISPLAY INVISIBLE (-2725 2950);
FORCEPROP 1 LAST BODY_TYPE PLUMBING
J 2
(-2725 2900);
DISPLAY 0.872340 (-2725 2900);
PAINT GREEN (-2725 2900);
DISPLAY INVISIBLE (-2725 2900);
FORCEPROP 1 LAST HDL_TAP TRUE
J 2
(-3050 2825);
DISPLAY 0.872340 (-3050 2825);
PAINT GREEN (-3050 2825);
DISPLAY INVISIBLE (-3050 2825);
FORCEPROP 1 LAST PATH I32
J 2
(-2723 2950);
DISPLAY 0.872340 (-2723 2950);
PAINT GREEN (-2723 2950);
DISPLAY INVISIBLE (-2723 2950);
FORCEADD TAP..6
R 2
(-2725 2850);
FORCEPROP 3 LASTPIN (-2775 2850) SIG_NAME DMI_CPU0_PCH_RX_DP<0>
J 0
(-2765 2860);
DISPLAY 0.659574 (-2765 2860);
PAINT MONO (-2765 2860);
DISPLAY INVISIBLE (-2765 2860);
FORCEPROP 1 LASTPIN (-2775 2850) BN 0
J 2
(-2723 2858);
DISPLAY 0.617021 (-2723 2858);
PAINT VIOLET (-2723 2858);
FORCEPROP 2 LAST CDS_LIB mstr_standard
J 0
(-2725 2850);
PAINT ORANGE (-2725 2850);
DISPLAY INVISIBLE (-2725 2850);
FORCEPROP 2 LAST BOM_COST SB
J 0
(-2750 2900);
DISPLAY 0.744681 (-2750 2900);
PAINT MONO (-2750 2900);
DISPLAY INVISIBLE (-2750 2900);
FORCEPROP 1 LAST BODY_TYPE PLUMBING
J 2
(-2725 2800);
DISPLAY 0.872340 (-2725 2800);
PAINT GREEN (-2725 2800);
DISPLAY INVISIBLE (-2725 2800);
FORCEPROP 1 LAST HDL_TAP TRUE
J 2
(-3050 2725);
DISPLAY 0.872340 (-3050 2725);
PAINT GREEN (-3050 2725);
DISPLAY INVISIBLE (-3050 2725);
FORCEPROP 1 LAST PATH I33
J 2
(-2723 2850);
DISPLAY 0.872340 (-2723 2850);
PAINT GREEN (-2723 2850);
DISPLAY INVISIBLE (-2723 2850);
FORCEADD TAP..6
R 2
(-2600 3000);
FORCEPROP 3 LASTPIN (-2650 3000) SIG_NAME DMI_CPU0_PCH_RX_DN<2>
J 0
(-2640 3010);
DISPLAY 0.659574 (-2640 3010);
PAINT MONO (-2640 3010);
DISPLAY INVISIBLE (-2640 3010);
FORCEPROP 1 LASTPIN (-2650 3000) BN 2
J 2
(-2598 3008);
DISPLAY 0.617021 (-2598 3008);
PAINT VIOLET (-2598 3008);
FORCEPROP 2 LAST BOM_COST SB
J 0
(-2625 3050);
DISPLAY 0.744681 (-2625 3050);
PAINT MONO (-2625 3050);
DISPLAY INVISIBLE (-2625 3050);
FORCEPROP 2 LAST CDS_LIB mstr_standard
J 0
(-2600 3000);
PAINT ORANGE (-2600 3000);
DISPLAY INVISIBLE (-2600 3000);
FORCEPROP 1 LAST BODY_TYPE PLUMBING
J 2
(-2600 2950);
DISPLAY 0.872340 (-2600 2950);
PAINT GREEN (-2600 2950);
DISPLAY INVISIBLE (-2600 2950);
FORCEPROP 1 LAST HDL_TAP TRUE
J 2
(-2925 2875);
DISPLAY 0.872340 (-2925 2875);
PAINT GREEN (-2925 2875);
DISPLAY INVISIBLE (-2925 2875);
FORCEPROP 1 LAST PATH I34
J 2
(-2598 3000);
DISPLAY 0.872340 (-2598 3000);
PAINT GREEN (-2598 3000);
DISPLAY INVISIBLE (-2598 3000);
FORCEADD TAP..6
R 2
(-2600 2900);
FORCEPROP 3 LASTPIN (-2650 2900) SIG_NAME DMI_CPU0_PCH_RX_DN<1>
J 0
(-2640 2910);
DISPLAY 0.659574 (-2640 2910);
PAINT MONO (-2640 2910);
DISPLAY INVISIBLE (-2640 2910);
FORCEPROP 1 LASTPIN (-2650 2900) BN 1
J 2
(-2598 2908);
DISPLAY 0.617021 (-2598 2908);
PAINT VIOLET (-2598 2908);
FORCEPROP 2 LAST BOM_COST SB
J 0
(-2625 2950);
DISPLAY 0.744681 (-2625 2950);
PAINT MONO (-2625 2950);
DISPLAY INVISIBLE (-2625 2950);
FORCEPROP 2 LAST CDS_LIB mstr_standard
J 0
(-2600 2900);
PAINT ORANGE (-2600 2900);
DISPLAY INVISIBLE (-2600 2900);
FORCEPROP 1 LAST BODY_TYPE PLUMBING
J 2
(-2600 2850);
DISPLAY 0.872340 (-2600 2850);
PAINT GREEN (-2600 2850);
DISPLAY INVISIBLE (-2600 2850);
FORCEPROP 1 LAST HDL_TAP TRUE
J 2
(-2925 2775);
DISPLAY 0.872340 (-2925 2775);
PAINT GREEN (-2925 2775);
DISPLAY INVISIBLE (-2925 2775);
FORCEPROP 1 LAST PATH I35
J 2
(-2598 2900);
DISPLAY 0.872340 (-2598 2900);
PAINT GREEN (-2598 2900);
DISPLAY INVISIBLE (-2598 2900);
FORCEADD TAP..6
R 2
(-2600 2800);
FORCEPROP 3 LASTPIN (-2650 2800) SIG_NAME DMI_CPU0_PCH_RX_DN<0>
J 0
(-2640 2810);
DISPLAY 0.659574 (-2640 2810);
PAINT MONO (-2640 2810);
DISPLAY INVISIBLE (-2640 2810);
FORCEPROP 1 LASTPIN (-2650 2800) BN 0
J 2
(-2598 2808);
DISPLAY 0.617021 (-2598 2808);
PAINT VIOLET (-2598 2808);
FORCEPROP 2 LAST CDS_LIB mstr_standard
J 0
(-2600 2800);
PAINT ORANGE (-2600 2800);
DISPLAY INVISIBLE (-2600 2800);
FORCEPROP 2 LAST BOM_COST SB
J 0
(-2625 2850);
DISPLAY 0.744681 (-2625 2850);
PAINT MONO (-2625 2850);
DISPLAY INVISIBLE (-2625 2850);
FORCEPROP 1 LAST BODY_TYPE PLUMBING
J 2
(-2600 2750);
DISPLAY 0.872340 (-2600 2750);
PAINT GREEN (-2600 2750);
DISPLAY INVISIBLE (-2600 2750);
FORCEPROP 1 LAST HDL_TAP TRUE
J 2
(-2925 2675);
DISPLAY 0.872340 (-2925 2675);
PAINT GREEN (-2925 2675);
DISPLAY INVISIBLE (-2925 2675);
FORCEPROP 1 LAST PATH I36
J 2
(-2598 2800);
DISPLAY 0.872340 (-2598 2800);
PAINT GREEN (-2598 2800);
DISPLAY INVISIBLE (-2598 2800);
FORCEADD OFFPAGE..2
(-1700 3350);
FORCEPROP 2 LAST $XR0 129 
J 0
(-1511 3350);
DISPLAY 0.638298 (-1511 3350);
PAINT MONO (-1511 3350);
FORCEPROP 2 LAST BOM_COST SB
J 0
(-1950 3400);
DISPLAY 0.744681 (-1950 3400);
PAINT MONO (-1950 3400);
DISPLAY INVISIBLE (-1950 3400);
FORCEPROP 2 LAST CDS_LIB mstr_standard
J 0
(-1700 3350);
PAINT ORANGE (-1700 3350);
DISPLAY INVISIBLE (-1700 3350);
FORCEPROP 1 LAST OFFPAGE TRUE
J 0
(-1375 3225);
DISPLAY 0.872340 (-1375 3225);
PAINT GREEN (-1375 3225);
DISPLAY INVISIBLE (-1375 3225);
FORCEPROP 1 LAST COMMENT_BODY TRUE
J 0
(-1745 3255);
DISPLAY 0.872340 (-1745 3255);
PAINT PEACH (-1745 3255);
DISPLAY INVISIBLE (-1745 3255);
FORCEPROP 2 LAST PATH I38
J 0
(-1525 3425);
DISPLAY 1.021277 (-1525 3425);
PAINT ORANGE (-1525 3425);
DISPLAY INVISIBLE (-1525 3425);
FORCEADD OFFPAGE..2
(-1700 3250);
FORCEPROP 2 LAST $XR0 129 
J 0
(-1511 3250);
DISPLAY 0.638298 (-1511 3250);
PAINT MONO (-1511 3250);
FORCEPROP 2 LAST BOM_COST SB
J 0
(-1950 3300);
DISPLAY 0.744681 (-1950 3300);
PAINT MONO (-1950 3300);
DISPLAY INVISIBLE (-1950 3300);
FORCEPROP 2 LAST CDS_LIB mstr_standard
J 0
(-1700 3250);
PAINT ORANGE (-1700 3250);
DISPLAY INVISIBLE (-1700 3250);
FORCEPROP 1 LAST OFFPAGE TRUE
J 0
(-1375 3125);
DISPLAY 0.872340 (-1375 3125);
PAINT GREEN (-1375 3125);
DISPLAY INVISIBLE (-1375 3125);
FORCEPROP 1 LAST COMMENT_BODY TRUE
J 0
(-1745 3155);
DISPLAY 0.872340 (-1745 3155);
PAINT PEACH (-1745 3155);
DISPLAY INVISIBLE (-1745 3155);
FORCEPROP 2 LAST PATH I39
J 0
(-1525 3325);
DISPLAY 1.021277 (-1525 3325);
PAINT ORANGE (-1525 3325);
DISPLAY INVISIBLE (-1525 3325);
FORCEADD OFFPAGE..1
(-6975 1100);
FORCEPROP 2 LAST $XR0 107 
J 0
(-7227 1100);
DISPLAY 0.638298 (-7227 1100);
PAINT MONO (-7227 1100);
FORCEPROP 2 LAST CDS_LIB mstr_standard
J 0
(-6975 1100);
PAINT ORANGE (-6975 1100);
DISPLAY INVISIBLE (-6975 1100);
FORCEPROP 1 LAST OFFPAGE TRUE
J 0
(-6650 975);
DISPLAY 1.170213 (-6650 975);
PAINT GREEN (-6650 975);
DISPLAY INVISIBLE (-6650 975);
FORCEPROP 1 LAST COMMENT_BODY TRUE
J 0
(-6850 1000);
DISPLAY 1.170213 (-6850 1000);
PAINT PEACH (-6850 1000);
DISPLAY INVISIBLE (-6850 1000);
FORCEPROP 2 LAST PATH I40
J 0
(-7175 1150);
DISPLAY 1.021277 (-7175 1150);
PAINT ORANGE (-7175 1150);
DISPLAY INVISIBLE (-7175 1150);
FORCEADD OFFPAGE..1
(-6975 1025);
FORCEPROP 2 LAST $XR0 107 
J 0
(-7227 1025);
DISPLAY 0.638298 (-7227 1025);
PAINT MONO (-7227 1025);
FORCEPROP 2 LAST CDS_LIB mstr_standard
J 0
(-6975 1025);
PAINT ORANGE (-6975 1025);
DISPLAY INVISIBLE (-6975 1025);
FORCEPROP 1 LAST OFFPAGE TRUE
J 0
(-6650 900);
DISPLAY 1.170213 (-6650 900);
PAINT GREEN (-6650 900);
DISPLAY INVISIBLE (-6650 900);
FORCEPROP 1 LAST COMMENT_BODY TRUE
J 0
(-6850 925);
DISPLAY 1.170213 (-6850 925);
PAINT PEACH (-6850 925);
DISPLAY INVISIBLE (-6850 925);
FORCEPROP 2 LAST PATH I41
J 0
(-7175 1075);
DISPLAY 1.021277 (-7175 1075);
PAINT ORANGE (-7175 1075);
DISPLAY INVISIBLE (-7175 1075);
FORCEADD TAP..6
(-5625 1150);
FORCEPROP 3 LASTPIN (-5575 1150) SIG_NAME P3E_CPU0_PE1_PCH_TXN<0>
J 0
(-5565 1160);
DISPLAY 0.659574 (-5565 1160);
PAINT MONO (-5565 1160);
DISPLAY INVISIBLE (-5565 1160);
FORCEPROP 1 LASTPIN (-5575 1150) BN 0
J 0
(-5627 1158);
DISPLAY 0.617021 (-5627 1158);
PAINT VIOLET (-5627 1158);
FORCEPROP 2 LAST CDS_LIB mstr_standard
J 0
(-5625 1150);
PAINT ORANGE (-5625 1150);
DISPLAY INVISIBLE (-5625 1150);
FORCEPROP 1 LAST BODY_TYPE PLUMBING
J 0
(-5625 1100);
DISPLAY 1.170213 (-5625 1100);
PAINT GREEN (-5625 1100);
DISPLAY INVISIBLE (-5625 1100);
FORCEPROP 1 LAST HDL_TAP TRUE
J 0
(-5300 1025);
DISPLAY 1.170213 (-5300 1025);
PAINT ORANGE (-5300 1025);
DISPLAY INVISIBLE (-5300 1025);
FORCEPROP 1 LAST PATH I42
J 0
(-5627 1150);
DISPLAY 0.872340 (-5627 1150);
PAINT GREEN (-5627 1150);
DISPLAY INVISIBLE (-5627 1150);
FORCEADD TAP..6
(-5625 1250);
FORCEPROP 3 LASTPIN (-5575 1250) SIG_NAME P3E_CPU0_PE1_PCH_TXN<1>
J 0
(-5565 1260);
DISPLAY 0.659574 (-5565 1260);
PAINT MONO (-5565 1260);
DISPLAY INVISIBLE (-5565 1260);
FORCEPROP 1 LASTPIN (-5575 1250) BN 1
J 0
(-5627 1258);
DISPLAY 0.617021 (-5627 1258);
PAINT VIOLET (-5627 1258);
FORCEPROP 2 LAST CDS_LIB mstr_standard
J 0
(-5625 1250);
PAINT ORANGE (-5625 1250);
DISPLAY INVISIBLE (-5625 1250);
FORCEPROP 1 LAST BODY_TYPE PLUMBING
J 0
(-5625 1200);
DISPLAY 1.170213 (-5625 1200);
PAINT GREEN (-5625 1200);
DISPLAY INVISIBLE (-5625 1200);
FORCEPROP 1 LAST HDL_TAP TRUE
J 0
(-5300 1125);
DISPLAY 1.170213 (-5300 1125);
PAINT ORANGE (-5300 1125);
DISPLAY INVISIBLE (-5300 1125);
FORCEPROP 1 LAST PATH I43
J 0
(-5627 1250);
DISPLAY 0.872340 (-5627 1250);
PAINT GREEN (-5627 1250);
DISPLAY INVISIBLE (-5627 1250);
FORCEADD TAP..6
(-5625 1450);
FORCEPROP 3 LASTPIN (-5575 1450) SIG_NAME P3E_CPU0_PE1_PCH_TXN<3>
J 0
(-5565 1460);
DISPLAY 0.659574 (-5565 1460);
PAINT MONO (-5565 1460);
DISPLAY INVISIBLE (-5565 1460);
FORCEPROP 1 LASTPIN (-5575 1450) BN 3
J 0
(-5627 1458);
DISPLAY 0.617021 (-5627 1458);
PAINT VIOLET (-5627 1458);
FORCEPROP 2 LAST CDS_LIB mstr_standard
J 0
(-5625 1450);
PAINT ORANGE (-5625 1450);
DISPLAY INVISIBLE (-5625 1450);
FORCEPROP 1 LAST BODY_TYPE PLUMBING
J 0
(-5625 1400);
DISPLAY 1.170213 (-5625 1400);
PAINT GREEN (-5625 1400);
DISPLAY INVISIBLE (-5625 1400);
FORCEPROP 1 LAST HDL_TAP TRUE
J 0
(-5300 1325);
DISPLAY 1.170213 (-5300 1325);
PAINT ORANGE (-5300 1325);
DISPLAY INVISIBLE (-5300 1325);
FORCEPROP 1 LAST PATH I44
J 0
(-5627 1450);
DISPLAY 0.872340 (-5627 1450);
PAINT GREEN (-5627 1450);
DISPLAY INVISIBLE (-5627 1450);
FORCEADD TAP..6
(-5625 1350);
FORCEPROP 3 LASTPIN (-5575 1350) SIG_NAME P3E_CPU0_PE1_PCH_TXN<2>
J 0
(-5565 1360);
DISPLAY 0.659574 (-5565 1360);
PAINT MONO (-5565 1360);
DISPLAY INVISIBLE (-5565 1360);
FORCEPROP 1 LASTPIN (-5575 1350) BN 2
J 0
(-5627 1358);
DISPLAY 0.617021 (-5627 1358);
PAINT VIOLET (-5627 1358);
FORCEPROP 2 LAST CDS_LIB mstr_standard
J 0
(-5625 1350);
PAINT ORANGE (-5625 1350);
DISPLAY INVISIBLE (-5625 1350);
FORCEPROP 1 LAST BODY_TYPE PLUMBING
J 0
(-5625 1300);
DISPLAY 1.170213 (-5625 1300);
PAINT GREEN (-5625 1300);
DISPLAY INVISIBLE (-5625 1300);
FORCEPROP 1 LAST HDL_TAP TRUE
J 0
(-5300 1225);
DISPLAY 1.170213 (-5300 1225);
PAINT ORANGE (-5300 1225);
DISPLAY INVISIBLE (-5300 1225);
FORCEPROP 1 LAST PATH I45
J 0
(-5627 1350);
DISPLAY 0.872340 (-5627 1350);
PAINT GREEN (-5627 1350);
DISPLAY INVISIBLE (-5627 1350);
FORCEADD TAP..6
(-5625 1550);
FORCEPROP 3 LASTPIN (-5575 1550) SIG_NAME P3E_CPU0_PE1_PCH_TXN<4>
J 0
(-5565 1560);
DISPLAY 0.659574 (-5565 1560);
PAINT MONO (-5565 1560);
DISPLAY INVISIBLE (-5565 1560);
FORCEPROP 1 LASTPIN (-5575 1550) BN 4
J 0
(-5627 1558);
DISPLAY 0.617021 (-5627 1558);
PAINT VIOLET (-5627 1558);
FORCEPROP 2 LAST CDS_LIB mstr_standard
J 0
(-5625 1550);
PAINT ORANGE (-5625 1550);
DISPLAY INVISIBLE (-5625 1550);
FORCEPROP 1 LAST BODY_TYPE PLUMBING
J 0
(-5625 1500);
DISPLAY 1.170213 (-5625 1500);
PAINT GREEN (-5625 1500);
DISPLAY INVISIBLE (-5625 1500);
FORCEPROP 1 LAST HDL_TAP TRUE
J 0
(-5300 1425);
DISPLAY 1.170213 (-5300 1425);
PAINT ORANGE (-5300 1425);
DISPLAY INVISIBLE (-5300 1425);
FORCEPROP 1 LAST PATH I46
J 0
(-5627 1550);
DISPLAY 0.872340 (-5627 1550);
PAINT GREEN (-5627 1550);
DISPLAY INVISIBLE (-5627 1550);
FORCEADD TAP..6
(-5625 1650);
FORCEPROP 3 LASTPIN (-5575 1650) SIG_NAME P3E_CPU0_PE1_PCH_TXN<5>
J 0
(-5565 1660);
DISPLAY 0.659574 (-5565 1660);
PAINT MONO (-5565 1660);
DISPLAY INVISIBLE (-5565 1660);
FORCEPROP 1 LASTPIN (-5575 1650) BN 5
J 0
(-5627 1658);
DISPLAY 0.617021 (-5627 1658);
PAINT VIOLET (-5627 1658);
FORCEPROP 2 LAST CDS_LIB mstr_standard
J 0
(-5625 1650);
PAINT ORANGE (-5625 1650);
DISPLAY INVISIBLE (-5625 1650);
FORCEPROP 1 LAST BODY_TYPE PLUMBING
J 0
(-5625 1600);
DISPLAY 1.170213 (-5625 1600);
PAINT GREEN (-5625 1600);
DISPLAY INVISIBLE (-5625 1600);
FORCEPROP 1 LAST HDL_TAP TRUE
J 0
(-5300 1525);
DISPLAY 1.170213 (-5300 1525);
PAINT ORANGE (-5300 1525);
DISPLAY INVISIBLE (-5300 1525);
FORCEPROP 1 LAST PATH I47
J 0
(-5627 1650);
DISPLAY 0.872340 (-5627 1650);
PAINT GREEN (-5627 1650);
DISPLAY INVISIBLE (-5627 1650);
FORCEADD TAP..6
(-5625 1750);
FORCEPROP 3 LASTPIN (-5575 1750) SIG_NAME P3E_CPU0_PE1_PCH_TXN<6>
J 0
(-5565 1760);
DISPLAY 0.659574 (-5565 1760);
PAINT MONO (-5565 1760);
DISPLAY INVISIBLE (-5565 1760);
FORCEPROP 1 LASTPIN (-5575 1750) BN 6
J 0
(-5627 1758);
DISPLAY 0.617021 (-5627 1758);
PAINT VIOLET (-5627 1758);
FORCEPROP 2 LAST CDS_LIB mstr_standard
J 0
(-5625 1750);
PAINT ORANGE (-5625 1750);
DISPLAY INVISIBLE (-5625 1750);
FORCEPROP 1 LAST BODY_TYPE PLUMBING
J 0
(-5625 1700);
DISPLAY 1.170213 (-5625 1700);
PAINT GREEN (-5625 1700);
DISPLAY INVISIBLE (-5625 1700);
FORCEPROP 1 LAST HDL_TAP TRUE
J 0
(-5300 1625);
DISPLAY 1.170213 (-5300 1625);
PAINT ORANGE (-5300 1625);
DISPLAY INVISIBLE (-5300 1625);
FORCEPROP 1 LAST PATH I48
J 0
(-5627 1750);
DISPLAY 0.872340 (-5627 1750);
PAINT GREEN (-5627 1750);
DISPLAY INVISIBLE (-5627 1750);
FORCEADD TAP..6
(-5625 1850);
FORCEPROP 3 LASTPIN (-5575 1850) SIG_NAME P3E_CPU0_PE1_PCH_TXN<7>
J 0
(-5565 1860);
DISPLAY 0.659574 (-5565 1860);
PAINT MONO (-5565 1860);
DISPLAY INVISIBLE (-5565 1860);
FORCEPROP 1 LASTPIN (-5575 1850) BN 7
J 0
(-5627 1858);
DISPLAY 0.617021 (-5627 1858);
PAINT VIOLET (-5627 1858);
FORCEPROP 2 LAST CDS_LIB mstr_standard
J 0
(-5625 1850);
PAINT ORANGE (-5625 1850);
DISPLAY INVISIBLE (-5625 1850);
FORCEPROP 1 LAST BODY_TYPE PLUMBING
J 0
(-5625 1800);
DISPLAY 1.170213 (-5625 1800);
PAINT GREEN (-5625 1800);
DISPLAY INVISIBLE (-5625 1800);
FORCEPROP 1 LAST HDL_TAP TRUE
J 0
(-5300 1725);
DISPLAY 1.170213 (-5300 1725);
PAINT ORANGE (-5300 1725);
DISPLAY INVISIBLE (-5300 1725);
FORCEPROP 1 LAST PATH I50
J 0
(-5627 1850);
DISPLAY 0.872340 (-5627 1850);
PAINT GREEN (-5627 1850);
DISPLAY INVISIBLE (-5627 1850);
FORCEADD TAP..6
(-5500 1200);
FORCEPROP 3 LASTPIN (-5450 1200) SIG_NAME P3E_CPU0_PE1_PCH_TXP<0>
J 0
(-5440 1210);
DISPLAY 0.659574 (-5440 1210);
PAINT MONO (-5440 1210);
DISPLAY INVISIBLE (-5440 1210);
FORCEPROP 1 LASTPIN (-5450 1200) BN 0
J 0
(-5502 1208);
DISPLAY 0.617021 (-5502 1208);
PAINT VIOLET (-5502 1208);
FORCEPROP 2 LAST CDS_LIB mstr_standard
J 0
(-5500 1200);
PAINT ORANGE (-5500 1200);
DISPLAY INVISIBLE (-5500 1200);
FORCEPROP 1 LAST BODY_TYPE PLUMBING
J 0
(-5500 1150);
DISPLAY 1.170213 (-5500 1150);
PAINT GREEN (-5500 1150);
DISPLAY INVISIBLE (-5500 1150);
FORCEPROP 1 LAST HDL_TAP TRUE
J 0
(-5175 1075);
DISPLAY 1.170213 (-5175 1075);
PAINT ORANGE (-5175 1075);
DISPLAY INVISIBLE (-5175 1075);
FORCEPROP 1 LAST PATH I58
J 0
(-5502 1200);
DISPLAY 0.872340 (-5502 1200);
PAINT GREEN (-5502 1200);
DISPLAY INVISIBLE (-5502 1200);
FORCEADD TAP..6
(-5500 1300);
FORCEPROP 3 LASTPIN (-5450 1300) SIG_NAME P3E_CPU0_PE1_PCH_TXP<1>
J 0
(-5440 1310);
DISPLAY 0.659574 (-5440 1310);
PAINT MONO (-5440 1310);
DISPLAY INVISIBLE (-5440 1310);
FORCEPROP 1 LASTPIN (-5450 1300) BN 1
J 0
(-5502 1308);
DISPLAY 0.617021 (-5502 1308);
PAINT VIOLET (-5502 1308);
FORCEPROP 2 LAST CDS_LIB mstr_standard
J 0
(-5500 1300);
PAINT ORANGE (-5500 1300);
DISPLAY INVISIBLE (-5500 1300);
FORCEPROP 1 LAST BODY_TYPE PLUMBING
J 0
(-5500 1250);
DISPLAY 1.170213 (-5500 1250);
PAINT GREEN (-5500 1250);
DISPLAY INVISIBLE (-5500 1250);
FORCEPROP 1 LAST HDL_TAP TRUE
J 0
(-5175 1175);
DISPLAY 1.170213 (-5175 1175);
PAINT ORANGE (-5175 1175);
DISPLAY INVISIBLE (-5175 1175);
FORCEPROP 1 LAST PATH I59
J 0
(-5502 1300);
DISPLAY 0.872340 (-5502 1300);
PAINT GREEN (-5502 1300);
DISPLAY INVISIBLE (-5502 1300);
FORCEADD TAP..6
(-5500 1400);
FORCEPROP 3 LASTPIN (-5450 1400) SIG_NAME P3E_CPU0_PE1_PCH_TXP<2>
J 0
(-5440 1410);
DISPLAY 0.659574 (-5440 1410);
PAINT MONO (-5440 1410);
DISPLAY INVISIBLE (-5440 1410);
FORCEPROP 1 LASTPIN (-5450 1400) BN 2
J 0
(-5502 1408);
DISPLAY 0.617021 (-5502 1408);
PAINT VIOLET (-5502 1408);
FORCEPROP 2 LAST CDS_LIB mstr_standard
J 0
(-5500 1400);
PAINT ORANGE (-5500 1400);
DISPLAY INVISIBLE (-5500 1400);
FORCEPROP 1 LAST BODY_TYPE PLUMBING
J 0
(-5500 1350);
DISPLAY 1.170213 (-5500 1350);
PAINT GREEN (-5500 1350);
DISPLAY INVISIBLE (-5500 1350);
FORCEPROP 1 LAST HDL_TAP TRUE
J 0
(-5175 1275);
DISPLAY 1.170213 (-5175 1275);
PAINT ORANGE (-5175 1275);
DISPLAY INVISIBLE (-5175 1275);
FORCEPROP 1 LAST PATH I60
J 0
(-5502 1400);
DISPLAY 0.872340 (-5502 1400);
PAINT GREEN (-5502 1400);
DISPLAY INVISIBLE (-5502 1400);
FORCEADD TAP..6
(-5500 1500);
FORCEPROP 3 LASTPIN (-5450 1500) SIG_NAME P3E_CPU0_PE1_PCH_TXP<3>
J 0
(-5440 1510);
DISPLAY 0.659574 (-5440 1510);
PAINT MONO (-5440 1510);
DISPLAY INVISIBLE (-5440 1510);
FORCEPROP 1 LASTPIN (-5450 1500) BN 3
J 0
(-5502 1508);
DISPLAY 0.617021 (-5502 1508);
PAINT VIOLET (-5502 1508);
FORCEPROP 2 LAST CDS_LIB mstr_standard
J 0
(-5500 1500);
PAINT ORANGE (-5500 1500);
DISPLAY INVISIBLE (-5500 1500);
FORCEPROP 1 LAST BODY_TYPE PLUMBING
J 0
(-5500 1450);
DISPLAY 1.170213 (-5500 1450);
PAINT GREEN (-5500 1450);
DISPLAY INVISIBLE (-5500 1450);
FORCEPROP 1 LAST HDL_TAP TRUE
J 0
(-5175 1375);
DISPLAY 1.170213 (-5175 1375);
PAINT ORANGE (-5175 1375);
DISPLAY INVISIBLE (-5175 1375);
FORCEPROP 1 LAST PATH I61
J 0
(-5502 1500);
DISPLAY 0.872340 (-5502 1500);
PAINT GREEN (-5502 1500);
DISPLAY INVISIBLE (-5502 1500);
FORCEADD TAP..6
(-5500 1700);
FORCEPROP 3 LASTPIN (-5450 1700) SIG_NAME P3E_CPU0_PE1_PCH_TXP<5>
J 0
(-5440 1710);
DISPLAY 0.659574 (-5440 1710);
PAINT MONO (-5440 1710);
DISPLAY INVISIBLE (-5440 1710);
FORCEPROP 1 LASTPIN (-5450 1700) BN 5
J 0
(-5502 1708);
DISPLAY 0.617021 (-5502 1708);
PAINT VIOLET (-5502 1708);
FORCEPROP 2 LAST CDS_LIB mstr_standard
J 0
(-5500 1700);
PAINT ORANGE (-5500 1700);
DISPLAY INVISIBLE (-5500 1700);
FORCEPROP 1 LAST BODY_TYPE PLUMBING
J 0
(-5500 1650);
DISPLAY 1.170213 (-5500 1650);
PAINT GREEN (-5500 1650);
DISPLAY INVISIBLE (-5500 1650);
FORCEPROP 1 LAST HDL_TAP TRUE
J 0
(-5175 1575);
DISPLAY 1.170213 (-5175 1575);
PAINT ORANGE (-5175 1575);
DISPLAY INVISIBLE (-5175 1575);
FORCEPROP 1 LAST PATH I62
J 0
(-5502 1700);
DISPLAY 0.872340 (-5502 1700);
PAINT GREEN (-5502 1700);
DISPLAY INVISIBLE (-5502 1700);
FORCEADD TAP..6
(-5500 1600);
FORCEPROP 3 LASTPIN (-5450 1600) SIG_NAME P3E_CPU0_PE1_PCH_TXP<4>
J 0
(-5440 1610);
DISPLAY 0.659574 (-5440 1610);
PAINT MONO (-5440 1610);
DISPLAY INVISIBLE (-5440 1610);
FORCEPROP 1 LASTPIN (-5450 1600) BN 4
J 0
(-5502 1608);
DISPLAY 0.617021 (-5502 1608);
PAINT VIOLET (-5502 1608);
FORCEPROP 2 LAST CDS_LIB mstr_standard
J 0
(-5500 1600);
PAINT ORANGE (-5500 1600);
DISPLAY INVISIBLE (-5500 1600);
FORCEPROP 1 LAST BODY_TYPE PLUMBING
J 0
(-5500 1550);
DISPLAY 1.170213 (-5500 1550);
PAINT GREEN (-5500 1550);
DISPLAY INVISIBLE (-5500 1550);
FORCEPROP 1 LAST HDL_TAP TRUE
J 0
(-5175 1475);
DISPLAY 1.170213 (-5175 1475);
PAINT ORANGE (-5175 1475);
DISPLAY INVISIBLE (-5175 1475);
FORCEPROP 1 LAST PATH I63
J 0
(-5502 1600);
DISPLAY 0.872340 (-5502 1600);
PAINT GREEN (-5502 1600);
DISPLAY INVISIBLE (-5502 1600);
FORCEADD TAP..6
(-5500 1800);
FORCEPROP 3 LASTPIN (-5450 1800) SIG_NAME P3E_CPU0_PE1_PCH_TXP<6>
J 0
(-5440 1810);
DISPLAY 0.659574 (-5440 1810);
PAINT MONO (-5440 1810);
DISPLAY INVISIBLE (-5440 1810);
FORCEPROP 1 LASTPIN (-5450 1800) BN 6
J 0
(-5502 1808);
DISPLAY 0.617021 (-5502 1808);
PAINT VIOLET (-5502 1808);
FORCEPROP 2 LAST CDS_LIB mstr_standard
J 0
(-5500 1800);
PAINT ORANGE (-5500 1800);
DISPLAY INVISIBLE (-5500 1800);
FORCEPROP 1 LAST BODY_TYPE PLUMBING
J 0
(-5500 1750);
DISPLAY 1.170213 (-5500 1750);
PAINT GREEN (-5500 1750);
DISPLAY INVISIBLE (-5500 1750);
FORCEPROP 1 LAST HDL_TAP TRUE
J 0
(-5175 1675);
DISPLAY 1.170213 (-5175 1675);
PAINT ORANGE (-5175 1675);
DISPLAY INVISIBLE (-5175 1675);
FORCEPROP 1 LAST PATH I64
J 0
(-5502 1800);
DISPLAY 0.872340 (-5502 1800);
PAINT GREEN (-5502 1800);
DISPLAY INVISIBLE (-5502 1800);
FORCEADD TAP..6
(-5500 1900);
FORCEPROP 3 LASTPIN (-5450 1900) SIG_NAME P3E_CPU0_PE1_PCH_TXP<7>
J 0
(-5440 1910);
DISPLAY 0.659574 (-5440 1910);
PAINT MONO (-5440 1910);
DISPLAY INVISIBLE (-5440 1910);
FORCEPROP 1 LASTPIN (-5450 1900) BN 7
J 0
(-5502 1908);
DISPLAY 0.617021 (-5502 1908);
PAINT VIOLET (-5502 1908);
FORCEPROP 2 LAST CDS_LIB mstr_standard
J 0
(-5500 1900);
PAINT ORANGE (-5500 1900);
DISPLAY INVISIBLE (-5500 1900);
FORCEPROP 1 LAST BODY_TYPE PLUMBING
J 0
(-5500 1850);
DISPLAY 1.170213 (-5500 1850);
PAINT GREEN (-5500 1850);
DISPLAY INVISIBLE (-5500 1850);
FORCEPROP 1 LAST HDL_TAP TRUE
J 0
(-5175 1775);
DISPLAY 1.170213 (-5175 1775);
PAINT ORANGE (-5175 1775);
DISPLAY INVISIBLE (-5175 1775);
FORCEPROP 1 LAST PATH I65
J 0
(-5502 1900);
DISPLAY 0.872340 (-5502 1900);
PAINT GREEN (-5502 1900);
DISPLAY INVISIBLE (-5502 1900);
FORCEADD TAP..1
(-2725 1200);
FORCEPROP 3 LASTPIN (-2775 1200) SIG_NAME P3E_CPU0_PE1_PCH_RXP<0>
J 0
(-2765 1210);
DISPLAY 0.659574 (-2765 1210);
PAINT MONO (-2765 1210);
DISPLAY INVISIBLE (-2765 1210);
FORCEPROP 1 LASTPIN (-2775 1200) BN 0
J 0
(-2787 1208);
DISPLAY 0.617021 (-2787 1208);
PAINT VIOLET (-2787 1208);
FORCEPROP 2 LAST CDS_LIB mstr_standard
J 0
(-2725 1200);
PAINT ORANGE (-2725 1200);
DISPLAY INVISIBLE (-2725 1200);
FORCEPROP 1 LAST BODY_TYPE PLUMBING
J 0
(-2725 1250);
DISPLAY 1.170213 (-2725 1250);
PAINT GREEN (-2725 1250);
DISPLAY INVISIBLE (-2725 1250);
FORCEPROP 1 LAST HDL_TAP TRUE
J 0
(-2400 1075);
DISPLAY 1.170213 (-2400 1075);
PAINT ORANGE (-2400 1075);
DISPLAY INVISIBLE (-2400 1075);
FORCEPROP 1 LAST PATH I74
J 0
(-2727 1200);
DISPLAY 0.872340 (-2727 1200);
PAINT GREEN (-2727 1200);
DISPLAY INVISIBLE (-2727 1200);
FORCEADD TAP..1
(-2725 1300);
FORCEPROP 3 LASTPIN (-2775 1300) SIG_NAME P3E_CPU0_PE1_PCH_RXP<1>
J 0
(-2765 1310);
DISPLAY 0.659574 (-2765 1310);
PAINT MONO (-2765 1310);
DISPLAY INVISIBLE (-2765 1310);
FORCEPROP 1 LASTPIN (-2775 1300) BN 1
J 0
(-2787 1308);
DISPLAY 0.617021 (-2787 1308);
PAINT VIOLET (-2787 1308);
FORCEPROP 2 LAST CDS_LIB mstr_standard
J 0
(-2725 1300);
PAINT ORANGE (-2725 1300);
DISPLAY INVISIBLE (-2725 1300);
FORCEPROP 1 LAST BODY_TYPE PLUMBING
J 0
(-2725 1350);
DISPLAY 1.170213 (-2725 1350);
PAINT GREEN (-2725 1350);
DISPLAY INVISIBLE (-2725 1350);
FORCEPROP 1 LAST HDL_TAP TRUE
J 0
(-2400 1175);
DISPLAY 1.170213 (-2400 1175);
PAINT ORANGE (-2400 1175);
DISPLAY INVISIBLE (-2400 1175);
FORCEPROP 1 LAST PATH I75
J 0
(-2727 1300);
DISPLAY 0.872340 (-2727 1300);
PAINT GREEN (-2727 1300);
DISPLAY INVISIBLE (-2727 1300);
FORCEADD TAP..1
(-2725 1400);
FORCEPROP 3 LASTPIN (-2775 1400) SIG_NAME P3E_CPU0_PE1_PCH_RXP<2>
J 0
(-2765 1410);
DISPLAY 0.659574 (-2765 1410);
PAINT MONO (-2765 1410);
DISPLAY INVISIBLE (-2765 1410);
FORCEPROP 1 LASTPIN (-2775 1400) BN 2
J 0
(-2787 1408);
DISPLAY 0.617021 (-2787 1408);
PAINT VIOLET (-2787 1408);
FORCEPROP 2 LAST CDS_LIB mstr_standard
J 0
(-2725 1400);
PAINT ORANGE (-2725 1400);
DISPLAY INVISIBLE (-2725 1400);
FORCEPROP 1 LAST BODY_TYPE PLUMBING
J 0
(-2725 1450);
DISPLAY 1.170213 (-2725 1450);
PAINT GREEN (-2725 1450);
DISPLAY INVISIBLE (-2725 1450);
FORCEPROP 1 LAST HDL_TAP TRUE
J 0
(-2400 1275);
DISPLAY 1.170213 (-2400 1275);
PAINT ORANGE (-2400 1275);
DISPLAY INVISIBLE (-2400 1275);
FORCEPROP 1 LAST PATH I76
J 0
(-2727 1400);
DISPLAY 0.872340 (-2727 1400);
PAINT GREEN (-2727 1400);
DISPLAY INVISIBLE (-2727 1400);
FORCEADD TAP..1
(-2725 1500);
FORCEPROP 3 LASTPIN (-2775 1500) SIG_NAME P3E_CPU0_PE1_PCH_RXP<3>
J 0
(-2765 1510);
DISPLAY 0.659574 (-2765 1510);
PAINT MONO (-2765 1510);
DISPLAY INVISIBLE (-2765 1510);
FORCEPROP 1 LASTPIN (-2775 1500) BN 3
J 0
(-2787 1508);
DISPLAY 0.617021 (-2787 1508);
PAINT VIOLET (-2787 1508);
FORCEPROP 2 LAST CDS_LIB mstr_standard
J 0
(-2725 1500);
PAINT ORANGE (-2725 1500);
DISPLAY INVISIBLE (-2725 1500);
FORCEPROP 1 LAST BODY_TYPE PLUMBING
J 0
(-2725 1550);
DISPLAY 1.170213 (-2725 1550);
PAINT GREEN (-2725 1550);
DISPLAY INVISIBLE (-2725 1550);
FORCEPROP 1 LAST HDL_TAP TRUE
J 0
(-2400 1375);
DISPLAY 1.170213 (-2400 1375);
PAINT ORANGE (-2400 1375);
DISPLAY INVISIBLE (-2400 1375);
FORCEPROP 1 LAST PATH I77
J 0
(-2727 1500);
DISPLAY 0.872340 (-2727 1500);
PAINT GREEN (-2727 1500);
DISPLAY INVISIBLE (-2727 1500);
FORCEADD TAP..1
(-2725 1600);
FORCEPROP 3 LASTPIN (-2775 1600) SIG_NAME P3E_CPU0_PE1_PCH_RXP<4>
J 0
(-2765 1610);
DISPLAY 0.659574 (-2765 1610);
PAINT MONO (-2765 1610);
DISPLAY INVISIBLE (-2765 1610);
FORCEPROP 1 LASTPIN (-2775 1600) BN 4
J 0
(-2787 1608);
DISPLAY 0.617021 (-2787 1608);
PAINT VIOLET (-2787 1608);
FORCEPROP 2 LAST CDS_LIB mstr_standard
J 0
(-2725 1600);
PAINT ORANGE (-2725 1600);
DISPLAY INVISIBLE (-2725 1600);
FORCEPROP 1 LAST BODY_TYPE PLUMBING
J 0
(-2725 1650);
DISPLAY 1.170213 (-2725 1650);
PAINT GREEN (-2725 1650);
DISPLAY INVISIBLE (-2725 1650);
FORCEPROP 1 LAST HDL_TAP TRUE
J 0
(-2400 1475);
DISPLAY 1.170213 (-2400 1475);
PAINT ORANGE (-2400 1475);
DISPLAY INVISIBLE (-2400 1475);
FORCEPROP 1 LAST PATH I78
J 0
(-2727 1600);
DISPLAY 0.872340 (-2727 1600);
PAINT GREEN (-2727 1600);
DISPLAY INVISIBLE (-2727 1600);
FORCEADD TAP..1
(-2600 1250);
FORCEPROP 3 LASTPIN (-2650 1250) SIG_NAME P3E_CPU0_PE1_PCH_RXN<1>
J 0
(-2640 1260);
DISPLAY 0.659574 (-2640 1260);
PAINT MONO (-2640 1260);
DISPLAY INVISIBLE (-2640 1260);
FORCEPROP 1 LASTPIN (-2650 1250) BN 1
J 0
(-2662 1258);
DISPLAY 0.617021 (-2662 1258);
PAINT VIOLET (-2662 1258);
FORCEPROP 2 LAST CDS_LIB mstr_standard
J 0
(-2600 1250);
PAINT ORANGE (-2600 1250);
DISPLAY INVISIBLE (-2600 1250);
FORCEPROP 1 LAST BODY_TYPE PLUMBING
J 0
(-2600 1300);
DISPLAY 1.170213 (-2600 1300);
PAINT GREEN (-2600 1300);
DISPLAY INVISIBLE (-2600 1300);
FORCEPROP 1 LAST HDL_TAP TRUE
J 0
(-2275 1125);
DISPLAY 1.170213 (-2275 1125);
PAINT ORANGE (-2275 1125);
DISPLAY INVISIBLE (-2275 1125);
FORCEPROP 1 LAST PATH I79
J 0
(-2602 1250);
DISPLAY 0.872340 (-2602 1250);
PAINT GREEN (-2602 1250);
DISPLAY INVISIBLE (-2602 1250);
FORCEADD TAP..1
(-2600 1150);
FORCEPROP 3 LASTPIN (-2650 1150) SIG_NAME P3E_CPU0_PE1_PCH_RXN<0>
J 0
(-2640 1160);
DISPLAY 0.659574 (-2640 1160);
PAINT MONO (-2640 1160);
DISPLAY INVISIBLE (-2640 1160);
FORCEPROP 1 LASTPIN (-2650 1150) BN 0
J 0
(-2662 1158);
DISPLAY 0.617021 (-2662 1158);
PAINT VIOLET (-2662 1158);
FORCEPROP 2 LAST CDS_LIB mstr_standard
J 0
(-2600 1150);
PAINT ORANGE (-2600 1150);
DISPLAY INVISIBLE (-2600 1150);
FORCEPROP 1 LAST BODY_TYPE PLUMBING
J 0
(-2600 1200);
DISPLAY 1.170213 (-2600 1200);
PAINT GREEN (-2600 1200);
DISPLAY INVISIBLE (-2600 1200);
FORCEPROP 1 LAST HDL_TAP TRUE
J 0
(-2275 1025);
DISPLAY 1.170213 (-2275 1025);
PAINT ORANGE (-2275 1025);
DISPLAY INVISIBLE (-2275 1025);
FORCEPROP 1 LAST PATH I80
J 0
(-2602 1150);
DISPLAY 0.872340 (-2602 1150);
PAINT GREEN (-2602 1150);
DISPLAY INVISIBLE (-2602 1150);
FORCEADD TAP..1
(-2600 1350);
FORCEPROP 3 LASTPIN (-2650 1350) SIG_NAME P3E_CPU0_PE1_PCH_RXN<2>
J 0
(-2640 1360);
DISPLAY 0.659574 (-2640 1360);
PAINT MONO (-2640 1360);
DISPLAY INVISIBLE (-2640 1360);
FORCEPROP 1 LASTPIN (-2650 1350) BN 2
J 0
(-2662 1358);
DISPLAY 0.617021 (-2662 1358);
PAINT VIOLET (-2662 1358);
FORCEPROP 2 LAST CDS_LIB mstr_standard
J 0
(-2600 1350);
PAINT ORANGE (-2600 1350);
DISPLAY INVISIBLE (-2600 1350);
FORCEPROP 1 LAST BODY_TYPE PLUMBING
J 0
(-2600 1400);
DISPLAY 1.170213 (-2600 1400);
PAINT GREEN (-2600 1400);
DISPLAY INVISIBLE (-2600 1400);
FORCEPROP 1 LAST HDL_TAP TRUE
J 0
(-2275 1225);
DISPLAY 1.170213 (-2275 1225);
PAINT ORANGE (-2275 1225);
DISPLAY INVISIBLE (-2275 1225);
FORCEPROP 1 LAST PATH I81
J 0
(-2602 1350);
DISPLAY 0.872340 (-2602 1350);
PAINT GREEN (-2602 1350);
DISPLAY INVISIBLE (-2602 1350);
FORCEADD TAP..1
(-2600 1450);
FORCEPROP 3 LASTPIN (-2650 1450) SIG_NAME P3E_CPU0_PE1_PCH_RXN<3>
J 0
(-2640 1460);
DISPLAY 0.659574 (-2640 1460);
PAINT MONO (-2640 1460);
DISPLAY INVISIBLE (-2640 1460);
FORCEPROP 1 LASTPIN (-2650 1450) BN 3
J 0
(-2662 1458);
DISPLAY 0.617021 (-2662 1458);
PAINT VIOLET (-2662 1458);
FORCEPROP 2 LAST CDS_LIB mstr_standard
J 0
(-2600 1450);
PAINT ORANGE (-2600 1450);
DISPLAY INVISIBLE (-2600 1450);
FORCEPROP 1 LAST BODY_TYPE PLUMBING
J 0
(-2600 1500);
DISPLAY 1.170213 (-2600 1500);
PAINT GREEN (-2600 1500);
DISPLAY INVISIBLE (-2600 1500);
FORCEPROP 1 LAST HDL_TAP TRUE
J 0
(-2275 1325);
DISPLAY 1.170213 (-2275 1325);
PAINT ORANGE (-2275 1325);
DISPLAY INVISIBLE (-2275 1325);
FORCEPROP 1 LAST PATH I82
J 0
(-2602 1450);
DISPLAY 0.872340 (-2602 1450);
PAINT GREEN (-2602 1450);
DISPLAY INVISIBLE (-2602 1450);
FORCEADD TAP..1
(-2600 1650);
FORCEPROP 3 LASTPIN (-2650 1650) SIG_NAME P3E_CPU0_PE1_PCH_RXN<5>
J 0
(-2640 1660);
DISPLAY 0.659574 (-2640 1660);
PAINT MONO (-2640 1660);
DISPLAY INVISIBLE (-2640 1660);
FORCEPROP 1 LASTPIN (-2650 1650) BN 5
J 0
(-2662 1658);
DISPLAY 0.617021 (-2662 1658);
PAINT VIOLET (-2662 1658);
FORCEPROP 2 LAST CDS_LIB mstr_standard
J 0
(-2600 1650);
PAINT ORANGE (-2600 1650);
DISPLAY INVISIBLE (-2600 1650);
FORCEPROP 1 LAST BODY_TYPE PLUMBING
J 0
(-2600 1700);
DISPLAY 1.170213 (-2600 1700);
PAINT GREEN (-2600 1700);
DISPLAY INVISIBLE (-2600 1700);
FORCEPROP 1 LAST HDL_TAP TRUE
J 0
(-2275 1525);
DISPLAY 1.170213 (-2275 1525);
PAINT ORANGE (-2275 1525);
DISPLAY INVISIBLE (-2275 1525);
FORCEPROP 1 LAST PATH I83
J 0
(-2602 1650);
DISPLAY 0.872340 (-2602 1650);
PAINT GREEN (-2602 1650);
DISPLAY INVISIBLE (-2602 1650);
FORCEADD TAP..1
(-2600 1550);
FORCEPROP 3 LASTPIN (-2650 1550) SIG_NAME P3E_CPU0_PE1_PCH_RXN<4>
J 0
(-2640 1560);
DISPLAY 0.659574 (-2640 1560);
PAINT MONO (-2640 1560);
DISPLAY INVISIBLE (-2640 1560);
FORCEPROP 1 LASTPIN (-2650 1550) BN 4
J 0
(-2662 1558);
DISPLAY 0.617021 (-2662 1558);
PAINT VIOLET (-2662 1558);
FORCEPROP 2 LAST CDS_LIB mstr_standard
J 0
(-2600 1550);
PAINT ORANGE (-2600 1550);
DISPLAY INVISIBLE (-2600 1550);
FORCEPROP 1 LAST BODY_TYPE PLUMBING
J 0
(-2600 1600);
DISPLAY 1.170213 (-2600 1600);
PAINT GREEN (-2600 1600);
DISPLAY INVISIBLE (-2600 1600);
FORCEPROP 1 LAST HDL_TAP TRUE
J 0
(-2275 1425);
DISPLAY 1.170213 (-2275 1425);
PAINT ORANGE (-2275 1425);
DISPLAY INVISIBLE (-2275 1425);
FORCEPROP 1 LAST PATH I84
J 0
(-2602 1550);
DISPLAY 0.872340 (-2602 1550);
PAINT GREEN (-2602 1550);
DISPLAY INVISIBLE (-2602 1550);
FORCEADD TAP..1
(-2725 1700);
FORCEPROP 3 LASTPIN (-2775 1700) SIG_NAME P3E_CPU0_PE1_PCH_RXP<5>
J 0
(-2765 1710);
DISPLAY 0.659574 (-2765 1710);
PAINT MONO (-2765 1710);
DISPLAY INVISIBLE (-2765 1710);
FORCEPROP 1 LASTPIN (-2775 1700) BN 5
J 0
(-2787 1708);
DISPLAY 0.617021 (-2787 1708);
PAINT VIOLET (-2787 1708);
FORCEPROP 2 LAST CDS_LIB mstr_standard
J 0
(-2725 1700);
PAINT ORANGE (-2725 1700);
DISPLAY INVISIBLE (-2725 1700);
FORCEPROP 1 LAST BODY_TYPE PLUMBING
J 0
(-2725 1750);
DISPLAY 1.170213 (-2725 1750);
PAINT GREEN (-2725 1750);
DISPLAY INVISIBLE (-2725 1750);
FORCEPROP 1 LAST HDL_TAP TRUE
J 0
(-2400 1575);
DISPLAY 1.170213 (-2400 1575);
PAINT ORANGE (-2400 1575);
DISPLAY INVISIBLE (-2400 1575);
FORCEPROP 1 LAST PATH I85
J 0
(-2727 1700);
DISPLAY 0.872340 (-2727 1700);
PAINT GREEN (-2727 1700);
DISPLAY INVISIBLE (-2727 1700);
FORCEADD TAP..1
(-2725 1800);
FORCEPROP 3 LASTPIN (-2775 1800) SIG_NAME P3E_CPU0_PE1_PCH_RXP<6>
J 0
(-2765 1810);
DISPLAY 0.659574 (-2765 1810);
PAINT MONO (-2765 1810);
DISPLAY INVISIBLE (-2765 1810);
FORCEPROP 1 LASTPIN (-2775 1800) BN 6
J 0
(-2787 1808);
DISPLAY 0.617021 (-2787 1808);
PAINT VIOLET (-2787 1808);
FORCEPROP 2 LAST CDS_LIB mstr_standard
J 0
(-2725 1800);
PAINT ORANGE (-2725 1800);
DISPLAY INVISIBLE (-2725 1800);
FORCEPROP 1 LAST BODY_TYPE PLUMBING
J 0
(-2725 1850);
DISPLAY 1.170213 (-2725 1850);
PAINT GREEN (-2725 1850);
DISPLAY INVISIBLE (-2725 1850);
FORCEPROP 1 LAST HDL_TAP TRUE
J 0
(-2400 1675);
DISPLAY 1.170213 (-2400 1675);
PAINT ORANGE (-2400 1675);
DISPLAY INVISIBLE (-2400 1675);
FORCEPROP 1 LAST PATH I86
J 0
(-2727 1800);
DISPLAY 0.872340 (-2727 1800);
PAINT GREEN (-2727 1800);
DISPLAY INVISIBLE (-2727 1800);
FORCEADD TAP..1
(-2725 1900);
FORCEPROP 3 LASTPIN (-2775 1900) SIG_NAME P3E_CPU0_PE1_PCH_RXP<7>
J 0
(-2765 1910);
DISPLAY 0.659574 (-2765 1910);
PAINT MONO (-2765 1910);
DISPLAY INVISIBLE (-2765 1910);
FORCEPROP 1 LASTPIN (-2775 1900) BN 7
J 0
(-2787 1908);
DISPLAY 0.617021 (-2787 1908);
PAINT VIOLET (-2787 1908);
FORCEPROP 2 LAST CDS_LIB mstr_standard
J 0
(-2725 1900);
PAINT ORANGE (-2725 1900);
DISPLAY INVISIBLE (-2725 1900);
FORCEPROP 1 LAST BODY_TYPE PLUMBING
J 0
(-2725 1950);
DISPLAY 1.170213 (-2725 1950);
PAINT GREEN (-2725 1950);
DISPLAY INVISIBLE (-2725 1950);
FORCEPROP 1 LAST HDL_TAP TRUE
J 0
(-2400 1775);
DISPLAY 1.170213 (-2400 1775);
PAINT ORANGE (-2400 1775);
DISPLAY INVISIBLE (-2400 1775);
FORCEPROP 1 LAST PATH I87
J 0
(-2727 1900);
DISPLAY 0.872340 (-2727 1900);
PAINT GREEN (-2727 1900);
DISPLAY INVISIBLE (-2727 1900);
FORCEADD LBG_CORE_QAT_EXT_D..4
(-3925 2150);
FORCEPROP 1 LAST LOCATION U7C1
J 0
(-4675 3400);
DISPLAY 0.617021 (-4675 3400);
PAINT AQUA (-4675 3400);
FORCEPROP 1 LAST PART_NUMBER H91415-002
J 0
(-4675 950);
DISPLAY 0.617021 (-4675 950);
PAINT BLUE (-4675 950);
FORCEPROP 1 LAST MATERIAL IC
J 0
(-4675 3350);
DISPLAY 0.617021 (-4675 3350);
PAINT SKYBLUE (-4675 3350);
FORCEPROP 2 LASTPIN (-4725 3100) $PN C45
J 2
(-4735 3110);
DISPLAY 0.617021 (-4735 3110);
PAINT ORANGE (-4735 3110);
FORCEPROP 2 LASTPIN (-4725 3000) $PN D44
J 2
(-4735 3010);
DISPLAY 0.617021 (-4735 3010);
PAINT ORANGE (-4735 3010);
FORCEPROP 2 LASTPIN (-4725 2900) $PN C43
J 2
(-4735 2910);
DISPLAY 0.617021 (-4735 2910);
PAINT ORANGE (-4735 2910);
FORCEPROP 2 LASTPIN (-4725 2800) $PN D42
J 2
(-4735 2810);
DISPLAY 0.617021 (-4735 2810);
PAINT ORANGE (-4735 2810);
FORCEPROP 2 LASTPIN (-4725 3150) $PN A45
J 2
(-4735 3160);
DISPLAY 0.617021 (-4735 3160);
PAINT ORANGE (-4735 3160);
FORCEPROP 2 LASTPIN (-4725 3050) $PN B44
J 2
(-4735 3060);
DISPLAY 0.617021 (-4735 3060);
PAINT ORANGE (-4735 3060);
FORCEPROP 2 LASTPIN (-4725 2950) $PN A43
J 2
(-4735 2960);
DISPLAY 0.617021 (-4735 2960);
PAINT ORANGE (-4735 2960);
FORCEPROP 2 LASTPIN (-4725 2850) $PN B42
J 2
(-4735 2860);
DISPLAY 0.617021 (-4735 2860);
PAINT ORANGE (-4735 2860);
FORCEPROP 2 LASTPIN (-3125 3100) $PN P52
J 0
(-3115 3110);
DISPLAY 0.617021 (-3115 3110);
PAINT ORANGE (-3115 3110);
FORCEPROP 2 LASTPIN (-3125 3000) $PN K50
J 0
(-3115 3010);
DISPLAY 0.617021 (-3115 3010);
PAINT ORANGE (-3115 3010);
FORCEPROP 2 LASTPIN (-3125 2900) $PN J48
J 0
(-3115 2910);
DISPLAY 0.617021 (-3115 2910);
PAINT ORANGE (-3115 2910);
FORCEPROP 2 LASTPIN (-3125 2800) $PN H46
J 0
(-3115 2810);
DISPLAY 0.617021 (-3115 2810);
PAINT ORANGE (-3115 2810);
FORCEPROP 2 LASTPIN (-3125 3150) $PN N54
J 0
(-3115 3160);
DISPLAY 0.617021 (-3115 3160);
PAINT ORANGE (-3115 3160);
FORCEPROP 2 LASTPIN (-3125 3050) $PN M52
J 0
(-3115 3060);
DISPLAY 0.617021 (-3115 3060);
PAINT ORANGE (-3115 3060);
FORCEPROP 2 LASTPIN (-3125 2950) $PN H50
J 0
(-3115 2960);
DISPLAY 0.617021 (-3115 2960);
PAINT ORANGE (-3115 2960);
FORCEPROP 2 LASTPIN (-3125 2850) $PN K46
J 0
(-3115 2860);
DISPLAY 0.617021 (-3115 2860);
PAINT ORANGE (-3115 2860);
FORCEPROP 2 LASTPIN (-4725 1150) $PN C48
J 2
(-4735 1160);
DISPLAY 0.617021 (-4735 1160);
PAINT ORANGE (-4735 1160);
FORCEPROP 2 LASTPIN (-4725 1200) $PN A48
J 2
(-4735 1210);
DISPLAY 0.617021 (-4735 1210);
PAINT ORANGE (-4735 1210);
FORCEPROP 2 LASTPIN (-3125 1150) $PN J52
J 0
(-3115 1160);
DISPLAY 0.617021 (-3115 1160);
PAINT ORANGE (-3115 1160);
FORCEPROP 2 LASTPIN (-3125 1200) $PN G52
J 0
(-3115 1210);
DISPLAY 0.617021 (-3115 1210);
PAINT ORANGE (-3115 1210);
FORCEPROP 2 LASTPIN (-4725 2150) $PN C59
J 2
(-4735 2160);
DISPLAY 0.617021 (-4735 2160);
PAINT ORANGE (-4735 2160);
FORCEPROP 2 LASTPIN (-4725 2200) $PN A59
J 2
(-4735 2210);
DISPLAY 0.617021 (-4735 2210);
PAINT ORANGE (-4735 2210);
FORCEPROP 2 LASTPIN (-3125 2150) $PN N65
J 0
(-3115 2160);
DISPLAY 0.617021 (-3115 2160);
PAINT ORANGE (-3115 2160);
FORCEPROP 2 LASTPIN (-3125 2200) $PN P66
J 0
(-3115 2210);
DISPLAY 0.617021 (-3115 2210);
PAINT ORANGE (-3115 2210);
FORCEPROP 2 LASTPIN (-4725 2250) $PN D60
J 2
(-4735 2260);
DISPLAY 0.617021 (-4735 2260);
PAINT ORANGE (-4735 2260);
FORCEPROP 2 LASTPIN (-4725 2300) $PN B60
J 2
(-4735 2310);
DISPLAY 0.617021 (-4735 2310);
PAINT ORANGE (-4735 2310);
FORCEPROP 2 LASTPIN (-3125 2250) $PN T59
J 0
(-3115 2260);
DISPLAY 0.617021 (-3115 2260);
PAINT ORANGE (-3115 2260);
FORCEPROP 2 LASTPIN (-3125 2300) $PN V59
J 0
(-3115 2310);
DISPLAY 0.617021 (-3115 2310);
PAINT ORANGE (-3115 2310);
FORCEPROP 2 LASTPIN (-4725 2350) $PN C61
J 2
(-4735 2360);
DISPLAY 0.617021 (-4735 2360);
PAINT ORANGE (-4735 2360);
FORCEPROP 2 LASTPIN (-4725 2400) $PN A61
J 2
(-4735 2410);
DISPLAY 0.617021 (-4735 2410);
PAINT ORANGE (-4735 2410);
FORCEPROP 2 LASTPIN (-3125 2350) $PN R65
J 0
(-3115 2360);
DISPLAY 0.617021 (-3115 2360);
PAINT ORANGE (-3115 2360);
FORCEPROP 2 LASTPIN (-3125 2400) $PN U65
J 0
(-3115 2410);
DISPLAY 0.617021 (-3115 2410);
PAINT ORANGE (-3115 2410);
FORCEPROP 2 LASTPIN (-4725 2450) $PN D62
J 2
(-4735 2460);
DISPLAY 0.617021 (-4735 2460);
PAINT ORANGE (-4735 2460);
FORCEPROP 2 LASTPIN (-4725 2500) $PN B62
J 2
(-4735 2510);
DISPLAY 0.617021 (-4735 2510);
PAINT ORANGE (-4735 2510);
FORCEPROP 2 LASTPIN (-3125 2450) $PN T63
J 0
(-3115 2460);
DISPLAY 0.617021 (-3115 2460);
PAINT ORANGE (-3115 2460);
FORCEPROP 2 LASTPIN (-3125 2500) $PN U61
J 0
(-3115 2510);
DISPLAY 0.617021 (-3115 2510);
PAINT ORANGE (-3115 2510);
FORCEPROP 2 LASTPIN (-4725 2550) $PN C63
J 2
(-4735 2560);
DISPLAY 0.617021 (-4735 2560);
PAINT ORANGE (-4735 2560);
FORCEPROP 2 LASTPIN (-4725 2600) $PN A63
J 2
(-4735 2610);
DISPLAY 0.617021 (-4735 2610);
PAINT ORANGE (-4735 2610);
FORCEPROP 2 LASTPIN (-3125 2550) $PN W65
J 0
(-3115 2560);
DISPLAY 0.617021 (-3115 2560);
PAINT ORANGE (-3115 2560);
FORCEPROP 2 LASTPIN (-3125 2600) $PN V63
J 0
(-3115 2610);
DISPLAY 0.617021 (-3115 2610);
PAINT ORANGE (-3115 2610);
FORCEPROP 2 LASTPIN (-4725 2650) $PN D64
J 2
(-4735 2660);
DISPLAY 0.617021 (-4735 2660);
PAINT ORANGE (-4735 2660);
FORCEPROP 2 LASTPIN (-4725 2700) $PN B64
J 2
(-4735 2710);
DISPLAY 0.617021 (-4735 2710);
PAINT ORANGE (-4735 2710);
FORCEPROP 2 LASTPIN (-3125 2650) $PN Y66
J 0
(-3115 2660);
DISPLAY 0.617021 (-3115 2660);
PAINT ORANGE (-3115 2660);
FORCEPROP 2 LASTPIN (-3125 2700) $PN AA65
J 0
(-3115 2710);
DISPLAY 0.617021 (-3115 2710);
PAINT ORANGE (-3115 2710);
FORCEPROP 2 LASTPIN (-4725 1250) $PN D49
J 2
(-4735 1260);
DISPLAY 0.617021 (-4735 1260);
PAINT ORANGE (-4735 1260);
FORCEPROP 2 LASTPIN (-4725 1300) $PN B49
J 2
(-4735 1310);
DISPLAY 0.617021 (-4735 1310);
PAINT ORANGE (-4735 1310);
FORCEPROP 2 LASTPIN (-3125 1250) $PN P56
J 0
(-3115 1260);
DISPLAY 0.617021 (-3115 1260);
PAINT ORANGE (-3115 1260);
FORCEPROP 2 LASTPIN (-3125 1300) $PN M56
J 0
(-3115 1310);
DISPLAY 0.617021 (-3115 1310);
PAINT ORANGE (-3115 1310);
FORCEPROP 2 LASTPIN (-4725 1350) $PN C50
J 2
(-4735 1360);
DISPLAY 0.617021 (-4735 1360);
PAINT ORANGE (-4735 1360);
FORCEPROP 2 LASTPIN (-4725 1400) $PN A50
J 2
(-4735 1410);
DISPLAY 0.617021 (-4735 1410);
PAINT ORANGE (-4735 1410);
FORCEPROP 2 LASTPIN (-3125 1350) $PN H54
J 0
(-3115 1360);
DISPLAY 0.617021 (-3115 1360);
PAINT ORANGE (-3115 1360);
FORCEPROP 2 LASTPIN (-3125 1400) $PN G56
J 0
(-3115 1410);
DISPLAY 0.617021 (-3115 1410);
PAINT ORANGE (-3115 1410);
FORCEPROP 2 LASTPIN (-4725 1450) $PN D51
J 2
(-4735 1460);
DISPLAY 0.617021 (-4735 1460);
PAINT ORANGE (-4735 1460);
FORCEPROP 2 LASTPIN (-4725 1500) $PN B51
J 2
(-4735 1510);
DISPLAY 0.617021 (-4735 1510);
PAINT ORANGE (-4735 1510);
FORCEPROP 2 LASTPIN (-3125 1450) $PN J56
J 0
(-3115 1460);
DISPLAY 0.617021 (-3115 1460);
PAINT ORANGE (-3115 1460);
FORCEPROP 2 LASTPIN (-3125 1500) $PN K58
J 0
(-3115 1510);
DISPLAY 0.617021 (-3115 1510);
PAINT ORANGE (-3115 1510);
FORCEPROP 2 LASTPIN (-4725 1550) $PN C52
J 2
(-4735 1560);
DISPLAY 0.617021 (-4735 1560);
PAINT ORANGE (-4735 1560);
FORCEPROP 2 LASTPIN (-4725 1600) $PN A52
J 2
(-4735 1610);
DISPLAY 0.617021 (-4735 1610);
PAINT ORANGE (-4735 1610);
FORCEPROP 2 LASTPIN (-3125 1550) $PN N58
J 0
(-3115 1560);
DISPLAY 0.617021 (-3115 1560);
PAINT ORANGE (-3115 1560);
FORCEPROP 2 LASTPIN (-3125 1600) $PN M59
J 0
(-3115 1610);
DISPLAY 0.617021 (-3115 1610);
PAINT ORANGE (-3115 1610);
FORCEPROP 2 LASTPIN (-4725 1650) $PN D53
J 2
(-4735 1660);
DISPLAY 0.617021 (-4735 1660);
PAINT ORANGE (-4735 1660);
FORCEPROP 2 LASTPIN (-4725 1700) $PN B53
J 2
(-4735 1710);
DISPLAY 0.617021 (-4735 1710);
PAINT ORANGE (-4735 1710);
FORCEPROP 2 LASTPIN (-3125 1650) $PN N61
J 0
(-3115 1660);
DISPLAY 0.617021 (-3115 1660);
PAINT ORANGE (-3115 1660);
FORCEPROP 2 LASTPIN (-3125 1700) $PN K61
J 0
(-3115 1710);
DISPLAY 0.617021 (-3115 1710);
PAINT ORANGE (-3115 1710);
FORCEPROP 2 LASTPIN (-4725 1750) $PN C54
J 2
(-4735 1760);
DISPLAY 0.617021 (-4735 1760);
PAINT ORANGE (-4735 1760);
FORCEPROP 2 LASTPIN (-4725 1800) $PN A54
J 2
(-4735 1810);
DISPLAY 0.617021 (-4735 1810);
PAINT ORANGE (-4735 1810);
FORCEPROP 2 LASTPIN (-3125 1750) $PN H61
J 0
(-3115 1760);
DISPLAY 0.617021 (-3115 1760);
PAINT ORANGE (-3115 1760);
FORCEPROP 2 LASTPIN (-3125 1800) $PN J63
J 0
(-3115 1810);
DISPLAY 0.617021 (-3115 1810);
PAINT ORANGE (-3115 1810);
FORCEPROP 2 LASTPIN (-4725 1850) $PN D55
J 2
(-4735 1860);
DISPLAY 0.617021 (-4735 1860);
PAINT ORANGE (-4735 1860);
FORCEPROP 2 LASTPIN (-4725 1900) $PN B55
J 2
(-4735 1910);
DISPLAY 0.617021 (-4735 1910);
PAINT ORANGE (-4735 1910);
FORCEPROP 2 LASTPIN (-3125 1850) $PN P59
J 0
(-3115 1860);
DISPLAY 0.617021 (-3115 1860);
PAINT ORANGE (-3115 1860);
FORCEPROP 2 LASTPIN (-3125 1900) $PN R61
J 0
(-3115 1910);
DISPLAY 0.617021 (-3115 1910);
PAINT ORANGE (-3115 1910);
FORCEPROP 2 LASTPIN (-4725 1950) $PN C57
J 2
(-4735 1960);
DISPLAY 0.617021 (-4735 1960);
PAINT ORANGE (-4735 1960);
FORCEPROP 2 LASTPIN (-4725 2000) $PN A57
J 2
(-4735 2010);
DISPLAY 0.617021 (-4735 2010);
PAINT ORANGE (-4735 2010);
FORCEPROP 2 LASTPIN (-3125 1950) $PN K65
J 0
(-3115 1960);
DISPLAY 0.617021 (-3115 1960);
PAINT ORANGE (-3115 1960);
FORCEPROP 2 LASTPIN (-3125 2000) $PN M63
J 0
(-3115 2010);
DISPLAY 0.617021 (-3115 2010);
PAINT ORANGE (-3115 2010);
FORCEPROP 2 LASTPIN (-4725 2050) $PN D58
J 2
(-4735 2060);
DISPLAY 0.617021 (-4735 2060);
PAINT ORANGE (-4735 2060);
FORCEPROP 2 LASTPIN (-4725 2100) $PN B58
J 2
(-4735 2110);
DISPLAY 0.617021 (-4735 2110);
PAINT ORANGE (-4735 2110);
FORCEPROP 2 LASTPIN (-3125 2050) $PN J66
J 0
(-3115 2060);
DISPLAY 0.617021 (-3115 2060);
PAINT ORANGE (-3115 2060);
FORCEPROP 2 LASTPIN (-3125 2100) $PN M66
J 0
(-3115 2110);
DISPLAY 0.617021 (-3115 2110);
PAINT ORANGE (-3115 2110);
FORCEPROP 1 LAST PACK_TYPE BGA1
J 0
(-4675 3450);
PAINT SKYBLUE (-4675 3450);
DISPLAY INVISIBLE (-4675 3450);
FORCEPROP 2 LAST SEC_TYPE BGA1
J 0
(-4675 3450);
DISPLAY 1.021277 (-4675 3450);
PAINT ORANGE (-4675 3450);
DISPLAY INVISIBLE (-4675 3450);
FORCEPROP 2 LAST SEC 4
J 0
(-4675 3450);
DISPLAY 0.680851 (-4675 3450);
PAINT MONO (-4675 3450);
DISPLAY INVISIBLE (-4675 3450);
FORCEPROP 2 LAST CDS_LIB mstr_u_proc
J 0
(-3925 2150);
PAINT ORANGE (-3925 2150);
DISPLAY INVISIBLE (-3925 2150);
FORCEPROP 0 LAST BOM_COST SB
J 0
(-4675 3600);
DISPLAY 1.361702 (-4675 3600);
PAINT ORANGE (-4675 3600);
DISPLAY INVISIBLE (-4675 3600);
FORCEPROP 2 LAST CDS_LOCATION U7C1
J 0
(-4675 3400);
DISPLAY 0.617021 (-4675 3400);
PAINT AQUA (-4675 3400);
DISPLAY INVISIBLE (-4675 3400);
FORCEPROP 1 LAST PATH I9
J 0
(-3925 3350);
PAINT GREEN (-3925 3350);
DISPLAY INVISIBLE (-3925 3350);
FORCEPROP 0 LAST ROOM SB
J 0
(-4675 3500);
DISPLAY 1.361702 (-4675 3500);
PAINT ORANGE (-4675 3500);
DISPLAY INVISIBLE (-4675 3500);
FORCEADD TAP..1
(-2600 1750);
FORCEPROP 3 LASTPIN (-2650 1750) SIG_NAME P3E_CPU0_PE1_PCH_RXN<6>
J 0
(-2640 1760);
DISPLAY 0.659574 (-2640 1760);
PAINT MONO (-2640 1760);
DISPLAY INVISIBLE (-2640 1760);
FORCEPROP 1 LASTPIN (-2650 1750) BN 6
J 0
(-2662 1758);
DISPLAY 0.617021 (-2662 1758);
PAINT VIOLET (-2662 1758);
FORCEPROP 2 LAST CDS_LIB mstr_standard
J 0
(-2600 1750);
PAINT ORANGE (-2600 1750);
DISPLAY INVISIBLE (-2600 1750);
FORCEPROP 1 LAST BODY_TYPE PLUMBING
J 0
(-2600 1800);
DISPLAY 1.170213 (-2600 1800);
PAINT GREEN (-2600 1800);
DISPLAY INVISIBLE (-2600 1800);
FORCEPROP 1 LAST HDL_TAP TRUE
J 0
(-2275 1625);
DISPLAY 1.170213 (-2275 1625);
PAINT ORANGE (-2275 1625);
DISPLAY INVISIBLE (-2275 1625);
FORCEPROP 1 LAST PATH I90
J 0
(-2602 1750);
DISPLAY 0.872340 (-2602 1750);
PAINT GREEN (-2602 1750);
DISPLAY INVISIBLE (-2602 1750);
FORCEADD TAP..1
(-2600 1850);
FORCEPROP 3 LASTPIN (-2650 1850) SIG_NAME P3E_CPU0_PE1_PCH_RXN<7>
J 0
(-2640 1860);
DISPLAY 0.659574 (-2640 1860);
PAINT MONO (-2640 1860);
DISPLAY INVISIBLE (-2640 1860);
FORCEPROP 1 LASTPIN (-2650 1850) BN 7
J 0
(-2662 1858);
DISPLAY 0.617021 (-2662 1858);
PAINT VIOLET (-2662 1858);
FORCEPROP 2 LAST CDS_LIB mstr_standard
J 0
(-2600 1850);
PAINT ORANGE (-2600 1850);
DISPLAY INVISIBLE (-2600 1850);
FORCEPROP 1 LAST BODY_TYPE PLUMBING
J 0
(-2600 1900);
DISPLAY 1.170213 (-2600 1900);
PAINT GREEN (-2600 1900);
DISPLAY INVISIBLE (-2600 1900);
FORCEPROP 1 LAST HDL_TAP TRUE
J 0
(-2275 1725);
DISPLAY 1.170213 (-2275 1725);
PAINT ORANGE (-2275 1725);
DISPLAY INVISIBLE (-2275 1725);
FORCEPROP 1 LAST PATH I91
J 0
(-2602 1850);
DISPLAY 0.872340 (-2602 1850);
PAINT GREEN (-2602 1850);
DISPLAY INVISIBLE (-2602 1850);
FORCEADD OFFPAGE..2
(-1325 1025);
FORCEPROP 2 LAST $XR0 107 
J 0
(-1136 1025);
DISPLAY 0.638298 (-1136 1025);
PAINT MONO (-1136 1025);
FORCEPROP 2 LAST CDS_LIB mstr_standard
J 0
(-1325 1025);
PAINT ORANGE (-1325 1025);
DISPLAY INVISIBLE (-1325 1025);
FORCEPROP 1 LAST OFFPAGE TRUE
J 0
(-1000 900);
DISPLAY 1.170213 (-1000 900);
PAINT GREEN (-1000 900);
DISPLAY INVISIBLE (-1000 900);
FORCEPROP 1 LAST COMMENT_BODY TRUE
J 0
(-1370 930);
DISPLAY 1.170213 (-1370 930);
PAINT PEACH (-1370 930);
DISPLAY INVISIBLE (-1370 930);
FORCEPROP 2 LAST PATH I95
J 0
(-1125 1075);
DISPLAY 1.021277 (-1125 1075);
PAINT ORANGE (-1125 1075);
DISPLAY INVISIBLE (-1125 1075);
FORCEADD OFFPAGE..2
(-1325 1100);
FORCEPROP 2 LAST $XR0 107 
J 0
(-1136 1100);
DISPLAY 0.638298 (-1136 1100);
PAINT MONO (-1136 1100);
FORCEPROP 2 LAST CDS_LIB mstr_standard
J 0
(-1325 1100);
PAINT ORANGE (-1325 1100);
DISPLAY INVISIBLE (-1325 1100);
FORCEPROP 1 LAST OFFPAGE TRUE
J 0
(-1000 975);
DISPLAY 1.170213 (-1000 975);
PAINT GREEN (-1000 975);
DISPLAY INVISIBLE (-1000 975);
FORCEPROP 1 LAST COMMENT_BODY TRUE
J 0
(-1370 1005);
DISPLAY 1.170213 (-1370 1005);
PAINT PEACH (-1370 1005);
DISPLAY INVISIBLE (-1370 1005);
FORCEPROP 2 LAST PATH I96
J 0
(-1125 1150);
DISPLAY 1.021277 (-1125 1150);
PAINT ORANGE (-1125 1150);
DISPLAY INVISIBLE (-1125 1150);
FORCEADD TAP..6
(-5500 2000);
FORCEPROP 3 LASTPIN (-5450 2000) SIG_NAME P3E_CPU0_PE1_PCH_C_TXN<8>
J 0
(-5440 2010);
DISPLAY 0.659574 (-5440 2010);
PAINT MONO (-5440 2010);
DISPLAY INVISIBLE (-5440 2010);
FORCEPROP 1 LASTPIN (-5450 2000) BN 8
J 0
(-5502 2008);
DISPLAY 0.617021 (-5502 2008);
PAINT GREEN (-5502 2008);
FORCEPROP 2 LAST CDS_LIB mstr_standard
J 0
(-5500 2000);
PAINT ORANGE (-5500 2000);
DISPLAY INVISIBLE (-5500 2000);
FORCEPROP 1 LAST BODY_TYPE PLUMBING
J 0
(-5500 1950);
DISPLAY 1.170213 (-5500 1950);
PAINT GREEN (-5500 1950);
DISPLAY INVISIBLE (-5500 1950);
FORCEPROP 1 LAST HDL_TAP TRUE
J 0
(-5175 1875);
DISPLAY 1.170213 (-5175 1875);
PAINT ORANGE (-5175 1875);
DISPLAY INVISIBLE (-5175 1875);
FORCEPROP 1 LAST PATH I97
J 0
(-5502 2000);
DISPLAY 0.872340 (-5502 2000);
PAINT GREEN (-5502 2000);
DISPLAY INVISIBLE (-5502 2000);
FORCEADD TAP..6
(-5500 2100);
FORCEPROP 3 LASTPIN (-5450 2100) SIG_NAME P3E_CPU0_PE1_PCH_C_TXN<9>
J 0
(-5440 2110);
DISPLAY 0.659574 (-5440 2110);
PAINT MONO (-5440 2110);
DISPLAY INVISIBLE (-5440 2110);
FORCEPROP 1 LASTPIN (-5450 2100) BN 9
J 0
(-5502 2108);
DISPLAY 0.617021 (-5502 2108);
PAINT GREEN (-5502 2108);
FORCEPROP 2 LAST CDS_LIB mstr_standard
J 0
(-5500 2100);
PAINT ORANGE (-5500 2100);
DISPLAY INVISIBLE (-5500 2100);
FORCEPROP 1 LAST BODY_TYPE PLUMBING
J 0
(-5500 2050);
DISPLAY 1.170213 (-5500 2050);
PAINT GREEN (-5500 2050);
DISPLAY INVISIBLE (-5500 2050);
FORCEPROP 1 LAST HDL_TAP TRUE
J 0
(-5175 1975);
DISPLAY 1.170213 (-5175 1975);
PAINT ORANGE (-5175 1975);
DISPLAY INVISIBLE (-5175 1975);
FORCEPROP 1 LAST PATH I98
J 0
(-5502 2100);
DISPLAY 0.872340 (-5502 2100);
PAINT GREEN (-5502 2100);
DISPLAY INVISIBLE (-5502 2100);
FORCEADD TAP..6
(-5500 2200);
FORCEPROP 3 LASTPIN (-5450 2200) SIG_NAME P3E_CPU0_PE1_PCH_C_TXN<10>
J 0
(-5440 2210);
DISPLAY 0.659574 (-5440 2210);
PAINT MONO (-5440 2210);
DISPLAY INVISIBLE (-5440 2210);
FORCEPROP 1 LASTPIN (-5450 2200) BN 10
J 0
(-5502 2208);
DISPLAY 0.617021 (-5502 2208);
PAINT GREEN (-5502 2208);
FORCEPROP 2 LAST CDS_LIB mstr_standard
J 0
(-5500 2200);
PAINT ORANGE (-5500 2200);
DISPLAY INVISIBLE (-5500 2200);
FORCEPROP 1 LAST BODY_TYPE PLUMBING
J 0
(-5500 2150);
DISPLAY 1.170213 (-5500 2150);
PAINT GREEN (-5500 2150);
DISPLAY INVISIBLE (-5500 2150);
FORCEPROP 1 LAST HDL_TAP TRUE
J 0
(-5175 2075);
DISPLAY 1.170213 (-5175 2075);
PAINT ORANGE (-5175 2075);
DISPLAY INVISIBLE (-5175 2075);
FORCEPROP 1 LAST PATH I99
J 0
(-5502 2200);
DISPLAY 0.872340 (-5502 2200);
PAINT GREEN (-5502 2200);
DISPLAY INVISIBLE (-5502 2200);
FORCEADD DESIGN_NOTE..1
(-1875 825);
FORCEPROP 0 LAST L2 TO PCH PCIEUP OR X24 SUPSERSLOT
J 0
(-2075 625);
DISPLAY 1.021277 (-2075 625);
PAINT ORANGE (-2075 625);
FORCEPROP 0 LAST L1 CPU0 HAS THE STEERING OPTION TO GO
J 0
(-2075 700);
DISPLAY 1.021277 (-2075 700);
PAINT ORANGE (-2075 700);
FORCEPROP 2 LAST CDS_LIB mstr_symbols
J 0
(-1875 825);
PAINT ORANGE (-1875 825);
DISPLAY INVISIBLE (-1875 825);
FORCEPROP 1 LAST COMMENT_BODY TRUE
J 0
(-1850 925);
DISPLAY 0.978723 (-1850 925);
PAINT ORANGE (-1850 925);
DISPLAY INVISIBLE (-1850 925);
FORCEADD DESIGN_NOTE..1
(-7375 2425);
FORCEPROP 0 LAST L2 INVERTED FOR EASE OF ROUTING
J 0
(-7575 2225);
DISPLAY 1.021277 (-7575 2225);
PAINT ORANGE (-7575 2225);
FORCEPROP 0 LAST L1 LANES 15:12, 10:8 ARE POLARITY
J 0
(-7575 2300);
DISPLAY 1.021277 (-7575 2300);
PAINT ORANGE (-7575 2300);
FORCEPROP 2 LAST CDS_LIB mstr_symbols
J 0
(-7375 2425);
PAINT ORANGE (-7375 2425);
DISPLAY INVISIBLE (-7375 2425);
FORCEPROP 1 LAST COMMENT_BODY TRUE
J 0
(-7350 2525);
DISPLAY 0.978723 (-7350 2525);
PAINT ORANGE (-7350 2525);
DISPLAY INVISIBLE (-7350 2525);
FORCEADD DESIGN_NOTE..1
(-6250 825);
FORCEPROP 0 LAST L1 CPU0 HAS THE STEERING OPTION TO GO
J 0
(-6450 700);
DISPLAY 1.021277 (-6450 700);
PAINT ORANGE (-6450 700);
FORCEPROP 0 LAST L2 TO PCH PCIEUP OR X24 SUPSERSLOT
J 0
(-6450 625);
DISPLAY 1.021277 (-6450 625);
PAINT ORANGE (-6450 625);
FORCEPROP 2 LAST CDS_LIB mstr_symbols
J 0
(-6250 825);
PAINT ORANGE (-6250 825);
DISPLAY INVISIBLE (-6250 825);
FORCEPROP 1 LAST COMMENT_BODY TRUE
J 0
(-6225 925);
DISPLAY 0.978723 (-6225 925);
PAINT ORANGE (-6225 925);
DISPLAY INVISIBLE (-6225 925);
FORCEADD INTEL_CORP_BPAGE..1
(0 0);
FORCEPROP 1 LAST CDS_CON_LAST_MODIFIED Tue Dec 01 11:51:56 2015
J 0
(-1425 325);
DISPLAY 1.340426 (-1425 325);
PAINT ORANGE (-1425 325);
DISPLAY INVISIBLE (-1425 325);
FORCEPROP 1 LAST CUSTOM_TXT_CDS <CURRENT_DESIGN_SHEET> OF <TOTAL_DESIGN_SHEETS>
J 0
(-500 25);
PAINT GREEN (-500 25);
FORCEPROP 1 LAST CUSTOM_TXT_CDS <CON_LAST_MODIFIED>
J 0
(-1925 350);
PAINT GREEN (-1925 350);
FORCEPROP 2 LAST CUSTOM_TXT_CDS <XR_PAGE_TITLE>
J 0
(-7890 5250);
DISPLAY 0.638298 (-7890 5250);
PAINT PINK (-7890 5250);
DISPLAY INVISIBLE (-7890 5250);
FORCEPROP 1 LAST SCH_ADDRESS3 Santa Clara, CA 95052-8119
J 0
(-3975 25);
DISPLAY 0.617021 (-3975 25);
PAINT YELLOW (-3975 25);
FORCEPROP 1 LAST SCH_ADDRESS2 P.O. BOX 58119
J 0
(-3975 75);
DISPLAY 0.617021 (-3975 75);
PAINT YELLOW (-3975 75);
FORCEPROP 1 LAST SCH_ADDRESS1 2200 Mission College Blvd.
J 0
(-3975 125);
DISPLAY 0.617021 (-3975 125);
PAINT YELLOW (-3975 125);
FORCEPROP 1 LAST SCH_TITLE LEWISBURG 4/11 DMI, PCIE
J 0
(-7950 50);
DISPLAY 1.212766 (-7950 50);
PAINT YELLOW (-7950 50);
FORCEPROP 1 LAST SCH_NUMBER H4694802
J 0
(-1300 150);
DISPLAY 1.212766 (-1300 150);
PAINT YELLOW (-1300 150);
FORCEPROP 1 LAST SCH_DEPT BESD
J 1
(-4450 100);
DISPLAY 1.212766 (-4450 100);
PAINT YELLOW (-4450 100);
FORCEPROP 1 LAST SCH_REV 2.420
J 0
(-250 150);
DISPLAY 0.978723 (-250 150);
PAINT YELLOW (-250 150);
FORCEPROP 2 LAST PAGE_BORDER TRUE
J 0
(-7890 5250);
DISPLAY 0.851064 (-7890 5250);
PAINT PINK (-7890 5250);
DISPLAY INVISIBLE (-7890 5250);
FORCEPROP 2 LAST CDS_LIB mstr_symbols
J 0
(0 0);
PAINT ORANGE (0 0);
DISPLAY INVISIBLE (0 0);
FORCEPROP 1 LAST COMMENT_BODY TRUE
J 0
(12 12);
DISPLAY 0.638298 (12 12);
PAINT PEACH (12 12);
DISPLAY INVISIBLE (12 12);
FORCEPROP 2 LAST CDS_XR_PAGE_TITLE CR-117 : @BASEBOARD_FAB2_LIB.BASEBOARD_FAB2(SCH_1):PAGE117
J 0
(-7890 5250);
DISPLAY 0.638298 (-7890 5250);
PAINT PINK (-7890 5250);
DISPLAY INVISIBLE (-7890 5250);
WIRE 17 -1 (-2675 2025)(-2675 2125);
WIRE 17 -1 (-2675 2025)(-1425 2025);
FORCEPROP 2 LAST SIG_NAME P3E_CPU0_PE1_PCH_R_RXP<15:8>
J 0
(-2310 2035);
DISPLAY 0.617021 (-2310 2035);
PAINT ORANGE (-2310 2035);
WIRE 17 -1 (-2550 2075)(-2550 2175);
WIRE 17 -1 (-2550 1975)(-2550 2075);
WIRE 17 -1 (-2550 2175)(-2550 2275);
WIRE 17 -1 (-2550 2275)(-2550 2375);
WIRE 17 -1 (-2550 1975)(-2550 1950);
WIRE 17 -1 (-2550 1950)(-1400 1950);
FORCEPROP 2 LAST SIG_NAME P3E_CPU0_PE1_PCH_R_RXN<15:8>
J 0
(-2310 1960);
DISPLAY 0.617021 (-2310 1960);
PAINT ORANGE (-2310 1960);
WIRE 17 -1 (-2675 2625)(-2675 2725);
WIRE 17 -1 (-2675 2525)(-2675 2625);
WIRE 17 -1 (-2675 2425)(-2675 2525);
WIRE 17 -1 (-2675 2325)(-2675 2425);
WIRE 17 -1 (-2675 2225)(-2675 2325);
WIRE 17 -1 (-2675 2125)(-2675 2225);
WIRE 17 -1 (-2550 2575)(-2550 2675);
WIRE 17 -1 (-2550 2475)(-2550 2575);
WIRE 17 -1 (-2550 2375)(-2550 2475);
WIRE 17 -1 (-2675 2975)(-2675 2875);
WIRE 17 -1 (-2675 3075)(-2675 2975);
WIRE 17 -1 (-2675 3175)(-2675 3075);
WIRE 17 -1 (-2675 3350)(-2675 3175);
WIRE 17 -1 (-2675 3350)(-1750 3350);
FORCEPROP 2 LAST SIG_NAME DMI_CPU0_PCH_RX_DP<3:0>
J 0
(-2535 3360);
DISPLAY 0.617021 (-2535 3360);
PAINT ORANGE (-2535 3360);
WIRE 17 -1 (-2550 2925)(-2550 2825);
WIRE 17 -1 (-2550 3025)(-2550 2925);
WIRE 17 -1 (-2550 3125)(-2550 3025);
WIRE 17 -1 (-2550 3250)(-2550 3125);
WIRE 17 -1 (-1750 3250)(-2550 3250);
FORCEPROP 2 LAST SIG_NAME DMI_CPU0_PCH_RX_DN<3:0>
J 0
(-2535 3260);
DISPLAY 0.617021 (-2535 3260);
PAINT ORANGE (-2535 3260);
WIRE 17 -1 (-2675 1825)(-2675 1925);
WIRE 17 -1 (-2675 1825)(-2675 1725);
WIRE 17 -1 (-2675 1725)(-2675 1625);
WIRE 17 -1 (-2675 1625)(-2675 1525);
WIRE 17 -1 (-2675 1525)(-2675 1425);
WIRE 17 -1 (-2675 1425)(-2675 1325);
WIRE 17 -1 (-2675 1325)(-2675 1225);
WIRE 17 -1 (-2675 1225)(-2675 1025);
WIRE 17 -1 (-2675 1025)(-1375 1025);
FORCEPROP 0 LAST SIG_NAME P3E_CPU0_PE1_PCH_RXP<7:0>
J 2
(-1360 1035);
DISPLAY 0.617021 (-1360 1035);
PAINT ORANGE (-1360 1035);
WIRE 17 -1 (-2550 1775)(-2550 1875);
WIRE 17 -1 (-2550 1775)(-2550 1675);
WIRE 17 -1 (-2550 1675)(-2550 1575);
WIRE 17 -1 (-2550 1575)(-2550 1475);
WIRE 17 -1 (-2550 1475)(-2550 1375);
WIRE 17 -1 (-2550 1375)(-2550 1275);
WIRE 17 -1 (-2550 1275)(-2550 1175);
WIRE 17 -1 (-2550 1175)(-2550 1100);
WIRE 17 -1 (-2550 1100)(-1375 1100);
FORCEPROP 0 LAST SIG_NAME P3E_CPU0_PE1_PCH_RXN<7:0>
J 2
(-1360 1110);
DISPLAY 0.617021 (-1360 1110);
PAINT ORANGE (-1360 1110);
WIRE 17 -1 (-5550 2125)(-5550 2225);
WIRE 17 -1 (-5550 2025)(-5550 2125);
WIRE 17 -1 (-5550 2225)(-5550 2275);
WIRE 17 -1 (-5550 2275)(-5550 2425);
WIRE 17 -1 (-5550 2025)(-6650 2025);
FORCEPROP 2 LAST SIG_NAME P3E_CPU0_PE1_PCH_C_TXN<15:8>
J 0
(-6635 2035);
DISPLAY 0.617021 (-6635 2035);
PAINT ORANGE (-6635 2035);
WIRE 17 -1 (-5675 2075)(-5675 2175);
WIRE 17 -1 (-5675 1975)(-5675 2075);
WIRE 17 -1 (-5675 2175)(-5675 2325);
WIRE 17 -1 (-5675 2325)(-5675 2375);
WIRE 17 -1 (-5675 1975)(-5675 1925);
WIRE 17 -1 (-5675 1925)(-6650 1925);
FORCEPROP 2 LAST SIG_NAME P3E_CPU0_PE1_PCH_C_TXP<15:8>
J 0
(-6635 1935);
DISPLAY 0.617021 (-6635 1935);
PAINT ORANGE (-6635 1935);
WIRE 17 -1 (-5550 2725)(-5550 2625);
WIRE 17 -1 (-5550 2625)(-5550 2525);
WIRE 17 -1 (-5550 2525)(-5550 2425);
WIRE 17 -1 (-5675 2575)(-5675 2675);
WIRE 17 -1 (-5675 2475)(-5675 2575);
WIRE 17 -1 (-5675 2375)(-5675 2475);
WIRE 17 -1 (-5475 2975)(-5475 2875);
WIRE 17 -1 (-5475 3075)(-5475 2975);
WIRE 17 -1 (-5475 3175)(-5475 3075);
WIRE 17 -1 (-5475 3350)(-5475 3175);
WIRE 17 -1 (-6450 3350)(-5475 3350);
FORCEPROP 2 LAST SIG_NAME DMI_CPU0_PCH_TX_C_DP<3:0>
J 0
(-6435 3360);
DISPLAY 0.617021 (-6435 3360);
PAINT ORANGE (-6435 3360);
WIRE 17 -1 (-5625 2925)(-5625 2825);
WIRE 17 -1 (-5625 3025)(-5625 2925);
WIRE 17 -1 (-5625 3125)(-5625 3025);
WIRE 17 -1 (-5625 3250)(-5625 3125);
WIRE 17 -1 (-6450 3250)(-5625 3250);
FORCEPROP 2 LAST SIG_NAME DMI_CPU0_PCH_TX_C_DN<3:0>
J 0
(-6435 3260);
DISPLAY 0.617021 (-6435 3260);
PAINT ORANGE (-6435 3260);
WIRE 17 -1 (-5550 1825)(-5550 1925);
WIRE 17 -1 (-5550 1725)(-5550 1825);
WIRE 17 -1 (-5550 1625)(-5550 1725);
WIRE 17 -1 (-5550 1525)(-5550 1625);
WIRE 17 -1 (-5550 1425)(-5550 1525);
WIRE 17 -1 (-5550 1325)(-5550 1425);
WIRE 17 -1 (-5550 1225)(-5550 1325);
WIRE 17 -1 (-5550 1025)(-5550 1225);
WIRE 17 -1 (-5550 1025)(-6925 1025);
FORCEPROP 0 LAST SIG_NAME P3E_CPU0_PE1_PCH_TXP<7:0>
J 0
(-6910 1035);
DISPLAY 0.617021 (-6910 1035);
PAINT ORANGE (-6910 1035);
WIRE 17 -1 (-5675 1775)(-5675 1875);
WIRE 17 -1 (-5675 1775)(-5675 1675);
WIRE 17 -1 (-5675 1675)(-5675 1575);
WIRE 17 -1 (-5675 1575)(-5675 1475);
WIRE 17 -1 (-5675 1475)(-5675 1375);
WIRE 17 -1 (-5675 1375)(-5675 1275);
WIRE 17 -1 (-5675 1275)(-5675 1175);
WIRE 17 -1 (-5675 1175)(-5675 1100);
WIRE 17 -1 (-5675 1100)(-6925 1100);
FORCEPROP 0 LAST SIG_NAME P3E_CPU0_PE1_PCH_TXN<7:0>
J 0
(-6910 1110);
DISPLAY 0.617021 (-6910 1110);
PAINT ORANGE (-6910 1110);
WIRE 16 -1 (-4725 1150)(-5575 1150);
WIRE 16 -1 (-4725 1200)(-5450 1200);
WIRE 16 -1 (-5575 1250)(-4725 1250);
WIRE 16 -1 (-5450 1300)(-4725 1300);
WIRE 16 -1 (-5575 1350)(-4725 1350);
WIRE 16 -1 (-4725 1400)(-5450 1400);
WIRE 16 -1 (-5575 1450)(-4725 1450);
WIRE 16 -1 (-5450 1500)(-4725 1500);
WIRE 16 -1 (-4725 1550)(-5575 1550);
WIRE 16 -1 (-4725 1600)(-5450 1600);
WIRE 16 -1 (-5575 1650)(-4725 1650);
WIRE 16 -1 (-5450 1700)(-4725 1700);
WIRE 16 -1 (-4725 1750)(-5575 1750);
WIRE 16 -1 (-4725 1800)(-5450 1800);
WIRE 16 -1 (-5575 1850)(-4725 1850);
WIRE 16 -1 (-5450 1900)(-4725 1900);
WIRE 16 -1 (-4725 1950)(-5575 1950);
WIRE 16 -1 (-5450 2000)(-4725 2000);
WIRE 16 -1 (-5525 3100)(-4725 3100);
WIRE 16 -1 (-5525 3000)(-4725 3000);
WIRE 16 -1 (-5525 2900)(-4725 2900);
WIRE 16 -1 (-5525 2800)(-4725 2800);
WIRE 16 -1 (-5375 3150)(-4725 3150);
WIRE 16 -1 (-5375 3050)(-4725 3050);
WIRE 16 -1 (-5375 2950)(-4725 2950);
WIRE 16 -1 (-5375 2850)(-4725 2850);
WIRE 16 -1 (-4725 2150)(-5575 2150);
WIRE 16 -1 (-4725 2200)(-5450 2200);
WIRE 16 -1 (-4725 2250)(-5450 2250);
WIRE 16 -1 (-5575 2300)(-4725 2300);
WIRE 16 -1 (-4725 2350)(-5575 2350);
WIRE 16 -1 (-5450 2400)(-4725 2400);
WIRE 16 -1 (-4725 2450)(-5575 2450);
WIRE 16 -1 (-5450 2500)(-4725 2500);
WIRE 16 -1 (-4725 2550)(-5575 2550);
WIRE 16 -1 (-5450 2600)(-4725 2600);
WIRE 16 -1 (-4725 2650)(-5575 2650);
WIRE 16 -1 (-5450 2700)(-4725 2700);
WIRE 16 -1 (-4725 2050)(-5575 2050);
WIRE 16 -1 (-5450 2100)(-4725 2100);
WIRE 16 -1 (-3125 1150)(-2650 1150);
WIRE 16 -1 (-3125 1200)(-2775 1200);
WIRE 16 -1 (-2650 1250)(-3125 1250);
WIRE 16 -1 (-3125 1300)(-2775 1300);
WIRE 16 -1 (-2650 1350)(-3125 1350);
WIRE 16 -1 (-3125 1400)(-2775 1400);
WIRE 16 -1 (-2650 1450)(-3125 1450);
WIRE 16 -1 (-3125 1500)(-2775 1500);
WIRE 16 -1 (-2650 1550)(-3125 1550);
WIRE 16 -1 (-3125 1600)(-2775 1600);
WIRE 16 -1 (-2650 1650)(-3125 1650);
WIRE 16 -1 (-3125 1700)(-2775 1700);
WIRE 16 -1 (-2650 1750)(-3125 1750);
WIRE 16 -1 (-3125 1800)(-2775 1800);
WIRE 16 -1 (-2650 1850)(-3125 1850);
WIRE 16 -1 (-3125 1900)(-2775 1900);
WIRE 16 -1 (-2650 1950)(-3125 1950);
WIRE 16 -1 (-3125 2000)(-2775 2000);
WIRE 16 -1 (-3125 3100)(-2650 3100);
WIRE 16 -1 (-2650 3000)(-3125 3000);
WIRE 16 -1 (-2650 2900)(-3125 2900);
WIRE 16 -1 (-2650 2800)(-3125 2800);
WIRE 16 -1 (-3125 3150)(-2775 3150);
WIRE 16 -1 (-2775 3050)(-3125 3050);
WIRE 16 -1 (-2775 2950)(-3125 2950);
WIRE 16 -1 (-2775 2850)(-3125 2850);
WIRE 16 -1 (-2650 2150)(-3125 2150);
WIRE 16 -1 (-3125 2200)(-2775 2200);
WIRE 16 -1 (-2650 2250)(-3125 2250);
WIRE 16 -1 (-3125 2300)(-2775 2300);
WIRE 16 -1 (-2650 2350)(-3125 2350);
WIRE 16 -1 (-3125 2400)(-2775 2400);
WIRE 16 -1 (-2650 2450)(-3125 2450);
WIRE 16 -1 (-3125 2500)(-2775 2500);
WIRE 16 -1 (-2650 2550)(-3125 2550);
WIRE 16 -1 (-3125 2600)(-2775 2600);
WIRE 16 -1 (-2650 2650)(-3125 2650);
WIRE 16 -1 (-3125 2700)(-2775 2700);
WIRE 16 -1 (-2650 2050)(-3125 2050);
WIRE 16 -1 (-3125 2100)(-2775 2100);
FORCENOTE
CPU0 DMI
(-1775 3075) 0;
DISPLAY LEFT (-1775 3075);
DISPLAY 1.021277 (-1775 3075);
PAINT PURPLE (-1775 3075);
FORCENOTE
CPU0
(-1425 1800) 0;
DISPLAY LEFT (-1425 1800);
DISPLAY 1.021277 (-1425 1800);
PAINT PURPLE (-1425 1800);
FORCENOTE
CPU0
(-1325 875) 0;
DISPLAY LEFT (-1325 875);
DISPLAY 1.021277 (-1325 875);
PAINT PURPLE (-1325 875);
FORCENOTE
CPU0 DMI
(-6375 3150) 0;
DISPLAY LEFT (-6375 3150);
DISPLAY 1.021277 (-6375 3150);
PAINT PURPLE (-6375 3150);
FORCENOTE
CPU0
(-6750 1775) 0;
DISPLAY LEFT (-6750 1775);
DISPLAY 1.021277 (-6750 1775);
PAINT PURPLE (-6750 1775);
FORCENOTE
CPU0
(-6925 900) 0;
DISPLAY LEFT (-6925 900);
DISPLAY 1.021277 (-6925 900);
PAINT PURPLE (-6925 900);
FORCENOTE
ROOM=SB
(-7725 250) 0;
DISPLAY LEFT (-7725 250);
DISPLAY 1.021277 (-7725 250);
PAINT PURPLE (-7725 250);
QUIT
